(kicad_sch
	(version 20250114)
	(generator "eeschema")
	(generator_version "9.0")
	(paper "A3")
	(title_block
		(title "Environmental Sensor")
		(date "2023-06-07")
		(rev "1.1.0")
		(company "Antmicro Ltd")
		(comment 1 "www.antmicro.com")
	)
	(text "3V3 LDO,\n300mA max \noutput current"
		(exclude_from_sim no)
		(at 181.61 62.23 0)
		(effects
			(font
				(size 1.27 1.27)
			)
			(justify left bottom)
		)
	)
	(text "Island Qwiic connector"
		(exclude_from_sim no)
		(at 325.12 205.74 0)
		(effects
			(font
				(size 2.5 2.5)
				(thickness 0.5)
				(bold yes)
			)
			(justify left bottom)
		)
	)
	(text "FT232R USB UART\n"
		(exclude_from_sim no)
		(at 26.035 144.78 0)
		(effects
			(font
				(size 2.5 2.5)
				(thickness 0.5)
				(bold yes)
			)
			(justify left bottom)
		)
	)
	(text "STM32 Microcontroller"
		(exclude_from_sim no)
		(at 142.24 93.98 0)
		(effects
			(font
				(size 2.5 2.5)
				(thickness 0.5)
				(bold yes)
			)
			(justify left bottom)
		)
	)
	(text "3V3 Regulator"
		(exclude_from_sim no)
		(at 166.37 20.32 0)
		(effects
			(font
				(size 2.5 2.5)
				(thickness 0.5)
				(bold yes)
			)
			(justify left bottom)
		)
	)
	(text "90 Ohm diff"
		(exclude_from_sim no)
		(at 74.93 53.34 0)
		(effects
			(font
				(size 1.27 1.27)
			)
			(justify left bottom)
		)
	)
	(text "USB-C 2.0 Data & Power connector"
		(exclude_from_sim no)
		(at 15.24 20.32 0)
		(effects
			(font
				(size 2.5 2.5)
				(thickness 0.5)
				(bold yes)
			)
			(justify left bottom)
		)
	)
	(text "SDO pin sets \nBME280's I2C address.\n\nSDO		| I2C addr.\n======+=======\nHigh	| 0x77\nLow		| 0x76"
		(exclude_from_sim no)
		(at 341.63 186.69 0)
		(effects
			(font
				(size 1.27 1.27)
			)
			(justify left bottom)
		)
	)
	(text "	  A1 A2 pin sets \n	FRAM's I2C address.\n\nA2  	|A1  	| I2C addr.\n----------------------\nLow		|Low 	| 0x50 + A16\nLow		|High	| 0x52 + A16\nHigh	|Low 	| 0x54 + A16\nHigh	|High	| 0x56 + A16"
		(exclude_from_sim no)
		(at 316.23 83.82 0)
		(effects
			(font
				(size 1.27 1.27)
			)
			(justify left bottom)
		)
	)
	(text "90 Ohm diff"
		(exclude_from_sim no)
		(at 74.93 50.8 0)
		(effects
			(font
				(size 1.27 1.27)
			)
			(justify left bottom)
		)
	)
	(text "VBUS can be 5V only due to ESD diode V_RWM"
		(exclude_from_sim no)
		(at 52.07 30.48 0)
		(effects
			(font
				(size 1.27 1.27)
			)
			(justify left bottom)
		)
	)
	(text "Boot\nSelect"
		(exclude_from_sim no)
		(at 308.61 142.24 0)
		(effects
			(font
				(size 1.27 1.27)
			)
			(justify left bottom)
		)
	)
	(text "I2C pull-ups"
		(exclude_from_sim no)
		(at 358.14 25.4 0)
		(effects
			(font
				(size 2.5 2.5)
				(thickness 0.5)
				(bold yes)
			)
			(justify left bottom)
		)
	)
	(text "SENSOR ISLAND"
		(exclude_from_sim no)
		(at 325.12 96.52 0)
		(effects
			(font
				(size 2.5 2.5)
				(thickness 0.6)
				(bold yes)
			)
			(justify left bottom)
		)
	)
	(text "SHT45's I2C \ndevice address: 0x44"
		(exclude_from_sim no)
		(at 372.11 113.03 0)
		(effects
			(font
				(size 1.27 1.27)
			)
			(justify left bottom)
		)
	)
	(text "Mainland Qwiic connector"
		(exclude_from_sim no)
		(at 187.96 237.49 0)
		(effects
			(font
				(size 2.5 2.5)
				(thickness 0.5)
				(bold yes)
			)
			(justify left bottom)
		)
	)
	(text "FeRAM I2C Memory"
		(exclude_from_sim no)
		(at 254 20.32 0)
		(effects
			(font
				(size 2.5 2.5)
				(thickness 0.5)
				(bold yes)
			)
			(justify left bottom)
		)
	)
	(junction
		(at 218.44 208.28)
		(diameter 0)
		(color 0 0 0 0)
	)
	(junction
		(at 161.29 46.99)
		(diameter 0)
		(color 0 0 0 0)
	)
	(junction
		(at 107.95 163.83)
		(diameter 0)
		(color 0 0 0 0)
	)
	(junction
		(at 240.03 190.5)
		(diameter 0)
		(color 0 0 0 0)
	)
	(junction
		(at 208.28 251.46)
		(diameter 0)
		(color 0 0 0 0)
	)
	(junction
		(at 50.8 104.14)
		(diameter 0)
		(color 0 0 0 0)
	)
	(junction
		(at 342.9 220.98)
		(diameter 0)
		(color 0 0 0 0)
	)
	(junction
		(at 68.58 215.9)
		(diameter 0)
		(color 0 0 0 0)
	)
	(junction
		(at 290.83 71.12)
		(diameter 0)
		(color 0 0 0 0)
	)
	(junction
		(at 240.03 184.15)
		(diameter 0)
		(color 0 0 0 0)
	)
	(junction
		(at 364.49 223.52)
		(diameter 0)
		(color 0 0 0 0)
	)
	(junction
		(at 35.56 104.14)
		(diameter 0)
		(color 0 0 0 0)
	)
	(junction
		(at 316.23 53.34)
		(diameter 0)
		(color 0 0 0 0)
	)
	(junction
		(at 215.9 264.16)
		(diameter 0)
		(color 0 0 0 0)
	)
	(junction
		(at 287.02 204.47)
		(diameter 0)
		(color 0 0 0 0)
	)
	(junction
		(at 345.44 218.44)
		(diameter 0)
		(color 0 0 0 0)
	)
	(junction
		(at 251.46 109.22)
		(diameter 0)
		(color 0 0 0 0)
	)
	(junction
		(at 378.46 153.67)
		(diameter 0)
		(color 0 0 0 0)
	)
	(junction
		(at 287.02 191.77)
		(diameter 0)
		(color 0 0 0 0)
	)
	(junction
		(at 306.07 50.8)
		(diameter 0)
		(color 0 0 0 0)
	)
	(junction
		(at 264.16 109.22)
		(diameter 0)
		(color 0 0 0 0)
	)
	(junction
		(at 293.37 71.12)
		(diameter 0)
		(color 0 0 0 0)
	)
	(junction
		(at 276.86 33.02)
		(diameter 0)
		(color 0 0 0 0)
	)
	(junction
		(at 365.76 115.57)
		(diameter 0)
		(color 0 0 0 0)
	)
	(junction
		(at 45.72 177.8)
		(diameter 0)
		(color 0 0 0 0)
	)
	(junction
		(at 35.56 93.98)
		(diameter 0)
		(color 0 0 0 0)
	)
	(junction
		(at 200.66 146.05)
		(diameter 0)
		(color 0 0 0 0)
	)
	(junction
		(at 353.06 231.14)
		(diameter 0)
		(color 0 0 0 0)
	)
	(junction
		(at 35.56 83.82)
		(diameter 0)
		(color 0 0 0 0)
	)
	(junction
		(at 63.5 46.99)
		(diameter 0)
		(color 0 0 0 0)
	)
	(junction
		(at 299.72 191.77)
		(diameter 0)
		(color 0 0 0 0)
	)
	(junction
		(at 289.56 109.22)
		(diameter 0)
		(color 0 0 0 0)
	)
	(junction
		(at 204.47 109.22)
		(diameter 0)
		(color 0 0 0 0)
	)
	(junction
		(at 205.74 198.12)
		(diameter 0)
		(color 0 0 0 0)
	)
	(junction
		(at 287.02 161.29)
		(diameter 0)
		(color 0 0 0 0)
	)
	(junction
		(at 50.8 83.82)
		(diameter 0)
		(color 0 0 0 0)
	)
	(junction
		(at 375.92 153.67)
		(diameter 0)
		(color 0 0 0 0)
	)
	(junction
		(at 218.44 198.12)
		(diameter 0)
		(color 0 0 0 0)
	)
	(junction
		(at 68.58 213.36)
		(diameter 0)
		(color 0 0 0 0)
	)
	(junction
		(at 46.99 53.34)
		(diameter 0)
		(color 0 0 0 0)
	)
	(junction
		(at 231.14 109.22)
		(diameter 0)
		(color 0 0 0 0)
	)
	(junction
		(at 149.86 46.99)
		(diameter 0)
		(color 0 0 0 0)
	)
	(junction
		(at 387.35 153.67)
		(diameter 0)
		(color 0 0 0 0)
	)
	(junction
		(at 68.58 218.44)
		(diameter 0)
		(color 0 0 0 0)
	)
	(junction
		(at 299.72 204.47)
		(diameter 0)
		(color 0 0 0 0)
	)
	(junction
		(at 276.86 109.22)
		(diameter 0)
		(color 0 0 0 0)
	)
	(junction
		(at 114.3 50.8)
		(diameter 0)
		(color 0 0 0 0)
	)
	(junction
		(at 205.74 208.28)
		(diameter 0)
		(color 0 0 0 0)
	)
	(junction
		(at 48.26 50.8)
		(diameter 0)
		(color 0 0 0 0)
	)
	(junction
		(at 135.89 46.99)
		(diameter 0)
		(color 0 0 0 0)
	)
	(junction
		(at 133.35 180.34)
		(diameter 0)
		(color 0 0 0 0)
	)
	(junction
		(at 287.02 151.13)
		(diameter 0)
		(color 0 0 0 0)
	)
	(junction
		(at 74.93 95.25)
		(diameter 0)
		(color 0 0 0 0)
	)
	(junction
		(at 36.83 177.8)
		(diameter 0)
		(color 0 0 0 0)
	)
	(junction
		(at 87.63 46.99)
		(diameter 0)
		(color 0 0 0 0)
	)
	(junction
		(at 101.6 163.83)
		(diameter 0)
		(color 0 0 0 0)
	)
	(junction
		(at 388.62 50.8)
		(diameter 0)
		(color 0 0 0 0)
	)
	(junction
		(at 381 55.88)
		(diameter 0)
		(color 0 0 0 0)
	)
	(junction
		(at 111.76 53.34)
		(diameter 0)
		(color 0 0 0 0)
	)
	(junction
		(at 219.71 101.6)
		(diameter 0)
		(color 0 0 0 0)
	)
	(junction
		(at 219.71 109.22)
		(diameter 0)
		(color 0 0 0 0)
	)
	(junction
		(at 130.81 182.88)
		(diameter 0)
		(color 0 0 0 0)
	)
	(junction
		(at 306.07 146.05)
		(diameter 0)
		(color 0 0 0 0)
	)
	(junction
		(at 227.33 256.54)
		(diameter 0)
		(color 0 0 0 0)
	)
	(junction
		(at 50.8 93.98)
		(diameter 0)
		(color 0 0 0 0)
	)
	(junction
		(at 199.39 46.99)
		(diameter 0)
		(color 0 0 0 0)
	)
	(junction
		(at 205.74 254)
		(diameter 0)
		(color 0 0 0 0)
	)
	(junction
		(at 336.55 170.18)
		(diameter 0)
		(color 0 0 0 0)
	)
	(junction
		(at 78.74 91.44)
		(diameter 0)
		(color 0 0 0 0)
	)
	(no_connect
		(at 373.38 215.9)
	)
	(no_connect
		(at 96.52 210.82)
	)
	(no_connect
		(at 269.24 281.94)
	)
	(no_connect
		(at 241.3 163.83)
	)
	(no_connect
		(at 241.3 146.05)
	)
	(no_connect
		(at 44.45 60.96)
	)
	(no_connect
		(at 274.32 166.37)
	)
	(no_connect
		(at 241.3 171.45)
	)
	(no_connect
		(at 274.32 143.51)
	)
	(no_connect
		(at 274.32 158.75)
	)
	(no_connect
		(at 71.12 208.28)
	)
	(no_connect
		(at 274.32 173.99)
	)
	(no_connect
		(at 96.52 213.36)
	)
	(no_connect
		(at 241.3 156.21)
	)
	(no_connect
		(at 274.32 146.05)
	)
	(no_connect
		(at 269.24 261.62)
	)
	(no_connect
		(at 44.45 58.42)
	)
	(no_connect
		(at 96.52 208.28)
	)
	(no_connect
		(at 241.3 176.53)
	)
	(no_connect
		(at 241.3 161.29)
	)
	(no_connect
		(at 96.52 205.74)
	)
	(no_connect
		(at 71.12 205.74)
	)
	(no_connect
		(at 274.32 179.07)
	)
	(no_connect
		(at 269.24 271.78)
	)
	(no_connect
		(at 274.32 176.53)
	)
	(no_connect
		(at 274.32 156.21)
	)
	(no_connect
		(at 274.32 140.97)
	)
	(no_connect
		(at 274.32 153.67)
	)
	(no_connect
		(at 241.3 173.99)
	)
	(no_connect
		(at 274.32 171.45)
	)
	(no_connect
		(at 236.22 248.92)
	)
	(no_connect
		(at 241.3 148.59)
	)
	(wire
		(pts
			(xy 382.27 121.92) (xy 382.27 123.19)
		)
		(stroke
			(width 0)
			(type default)
		)
	)
	(wire
		(pts
			(xy 205.74 208.28) (xy 205.74 210.82)
		)
		(stroke
			(width 0)
			(type default)
		)
	)
	(wire
		(pts
			(xy 229.87 168.91) (xy 232.41 168.91)
		)
		(stroke
			(width 0)
			(type default)
		)
	)
	(wire
		(pts
			(xy 316.23 60.96) (xy 316.23 63.5)
		)
		(stroke
			(width 0)
			(type default)
		)
	)
	(wire
		(pts
			(xy 44.45 45.72) (xy 48.26 45.72)
		)
		(stroke
			(width 0)
			(type default)
		)
	)
	(wire
		(pts
			(xy 36.83 177.8) (xy 45.72 177.8)
		)
		(stroke
			(width 0)
			(type default)
		)
	)
	(wire
		(pts
			(xy 35.56 104.14) (xy 40.64 104.14)
		)
		(stroke
			(width 0)
			(type default)
		)
	)
	(wire
		(pts
			(xy 210.82 109.22) (xy 210.82 129.54)
		)
		(stroke
			(width 0)
			(type default)
		)
	)
	(wire
		(pts
			(xy 210.82 158.75) (xy 210.82 161.29)
		)
		(stroke
			(width 0)
			(type default)
		)
	)
	(wire
		(pts
			(xy 96.52 177.8) (xy 101.6 177.8)
		)
		(stroke
			(width 0)
			(type default)
		)
	)
	(wire
		(pts
			(xy 135.89 46.99) (xy 149.86 46.99)
		)
		(stroke
			(width 0)
			(type default)
		)
	)
	(wire
		(pts
			(xy 107.95 170.18) (xy 107.95 171.45)
		)
		(stroke
			(width 0)
			(type default)
		)
	)
	(wire
		(pts
			(xy 388.62 50.8) (xy 391.16 50.8)
		)
		(stroke
			(width 0)
			(type default)
		)
	)
	(wire
		(pts
			(xy 109.22 60.96) (xy 99.06 60.96)
		)
		(stroke
			(width 0)
			(type default)
		)
	)
	(wire
		(pts
			(xy 133.35 190.5) (xy 135.89 190.5)
		)
		(stroke
			(width 0)
			(type default)
		)
	)
	(wire
		(pts
			(xy 237.49 166.37) (xy 241.3 166.37)
		)
		(stroke
			(width 0)
			(type default)
		)
	)
	(wire
		(pts
			(xy 210.82 129.54) (xy 233.68 129.54)
		)
		(stroke
			(width 0)
			(type default)
		)
	)
	(wire
		(pts
			(xy 229.87 151.13) (xy 241.3 151.13)
		)
		(stroke
			(width 0)
			(type default)
		)
	)
	(wire
		(pts
			(xy 240.03 187.96) (xy 241.3 187.96)
		)
		(stroke
			(width 0)
			(type default)
		)
	)
	(wire
		(pts
			(xy 375.92 50.8) (xy 388.62 50.8)
		)
		(stroke
			(width 0)
			(type default)
		)
	)
	(wire
		(pts
			(xy 63.5 33.02) (xy 63.5 46.99)
		)
		(stroke
			(width 0)
			(type default)
		)
	)
	(wire
		(pts
			(xy 204.47 118.11) (xy 204.47 119.38)
		)
		(stroke
			(width 0)
			(type default)
		)
	)
	(wire
		(pts
			(xy 195.58 198.12) (xy 205.74 198.12)
		)
		(stroke
			(width 0)
			(type default)
		)
	)
	(wire
		(pts
			(xy 299.72 182.88) (xy 299.72 191.77)
		)
		(stroke
			(width 0)
			(type default)
		)
	)
	(wire
		(pts
			(xy 306.07 146.05) (xy 306.07 147.32)
		)
		(stroke
			(width 0)
			(type default)
		)
	)
	(wire
		(pts
			(xy 177.8 57.15) (xy 177.8 64.77)
		)
		(stroke
			(width 0)
			(type default)
		)
	)
	(wire
		(pts
			(xy 78.74 91.44) (xy 78.74 99.06)
		)
		(stroke
			(width 0)
			(type default)
		)
	)
	(wire
		(pts
			(xy 200.66 146.05) (xy 233.68 146.05)
		)
		(stroke
			(width 0)
			(type default)
		)
	)
	(wire
		(pts
			(xy 219.71 264.16) (xy 215.9 264.16)
		)
		(stroke
			(width 0)
			(type default)
		)
	)
	(wire
		(pts
			(xy 231.14 139.7) (xy 241.3 139.7)
		)
		(stroke
			(width 0)
			(type default)
		)
	)
	(wire
		(pts
			(xy 99.06 105.41) (xy 99.06 115.57)
		)
		(stroke
			(width 0)
			(type default)
		)
	)
	(wire
		(pts
			(xy 114.3 50.8) (xy 114.3 60.96)
		)
		(stroke
			(width 0)
			(type default)
		)
	)
	(wire
		(pts
			(xy 218.44 215.9) (xy 218.44 222.25)
		)
		(stroke
			(width 0)
			(type default)
		)
	)
	(wire
		(pts
			(xy 209.55 99.06) (xy 209.55 101.6)
		)
		(stroke
			(width 0)
			(type default)
		)
	)
	(wire
		(pts
			(xy 195.58 256.54) (xy 203.2 256.54)
		)
		(stroke
			(width 0)
			(type default)
		)
	)
	(wire
		(pts
			(xy 287.02 185.42) (xy 287.02 191.77)
		)
		(stroke
			(width 0)
			(type default)
		)
	)
	(wire
		(pts
			(xy 398.78 160.02) (xy 398.78 161.29)
		)
		(stroke
			(width 0)
			(type default)
		)
	)
	(wire
		(pts
			(xy 114.3 50.8) (xy 127 50.8)
		)
		(stroke
			(width 0)
			(type default)
		)
	)
	(wire
		(pts
			(xy 264.16 116.84) (xy 264.16 118.11)
		)
		(stroke
			(width 0)
			(type default)
		)
	)
	(wire
		(pts
			(xy 96.52 198.12) (xy 101.6 198.12)
		)
		(stroke
			(width 0)
			(type default)
		)
	)
	(wire
		(pts
			(xy 106.68 187.96) (xy 110.49 187.96)
		)
		(stroke
			(width 0)
			(type default)
		)
	)
	(wire
		(pts
			(xy 87.63 46.99) (xy 87.63 59.69)
		)
		(stroke
			(width 0)
			(type default)
		)
	)
	(wire
		(pts
			(xy 218.44 208.28) (xy 218.44 210.82)
		)
		(stroke
			(width 0)
			(type default)
		)
	)
	(wire
		(pts
			(xy 287.02 157.48) (xy 287.02 161.29)
		)
		(stroke
			(width 0)
			(type default)
		)
	)
	(wire
		(pts
			(xy 107.95 163.83) (xy 118.11 163.83)
		)
		(stroke
			(width 0)
			(type default)
		)
	)
	(wire
		(pts
			(xy 336.55 166.37) (xy 336.55 170.18)
		)
		(stroke
			(width 0)
			(type default)
		)
	)
	(wire
		(pts
			(xy 50.8 83.82) (xy 50.8 93.98)
		)
		(stroke
			(width 0)
			(type default)
		)
	)
	(wire
		(pts
			(xy 373.38 226.06) (xy 370.84 226.06)
		)
		(stroke
			(width 0)
			(type default)
		)
	)
	(wire
		(pts
			(xy 44.45 50.8) (xy 48.26 50.8)
		)
		(stroke
			(width 0)
			(type default)
		)
	)
	(wire
		(pts
			(xy 378.46 151.13) (xy 378.46 153.67)
		)
		(stroke
			(width 0)
			(type default)
		)
	)
	(wire
		(pts
			(xy 87.63 46.99) (xy 100.33 46.99)
		)
		(stroke
			(width 0)
			(type default)
		)
	)
	(wire
		(pts
			(xy 78.74 82.55) (xy 78.74 91.44)
		)
		(stroke
			(width 0)
			(type default)
		)
	)
	(wire
		(pts
			(xy 218.44 198.12) (xy 229.87 198.12)
		)
		(stroke
			(width 0)
			(type default)
		)
	)
	(polyline
		(pts
			(xy 137.16 132.08) (xy 186.69 132.08)
		)
		(stroke
			(width 0)
			(type dash)
		)
	)
	(wire
		(pts
			(xy 345.44 218.44) (xy 345.44 224.79)
		)
		(stroke
			(width 0)
			(type default)
		)
	)
	(polyline
		(pts
			(xy 353.06 12.7) (xy 353.06 86.36)
		)
		(stroke
			(width 0)
			(type dash)
		)
	)
	(wire
		(pts
			(xy 233.68 143.51) (xy 233.68 146.05)
		)
		(stroke
			(width 0)
			(type default)
		)
	)
	(wire
		(pts
			(xy 45.72 93.98) (xy 50.8 93.98)
		)
		(stroke
			(width 0)
			(type default)
		)
	)
	(wire
		(pts
			(xy 356.87 223.52) (xy 356.87 231.14)
		)
		(stroke
			(width 0)
			(type default)
		)
	)
	(wire
		(pts
			(xy 59.69 73.66) (xy 59.69 76.2)
		)
		(stroke
			(width 0)
			(type default)
		)
	)
	(wire
		(pts
			(xy 233.68 137.16) (xy 241.3 137.16)
		)
		(stroke
			(width 0)
			(type default)
		)
	)
	(wire
		(pts
			(xy 71.12 180.34) (xy 68.58 180.34)
		)
		(stroke
			(width 0)
			(type default)
		)
	)
	(polyline
		(pts
			(xy 137.16 132.08) (xy 137.16 86.36)
		)
		(stroke
			(width 0)
			(type dash)
		)
	)
	(wire
		(pts
			(xy 78.74 91.44) (xy 99.06 91.44)
		)
		(stroke
			(width 0)
			(type default)
		)
	)
	(wire
		(pts
			(xy 260.35 38.1) (xy 260.35 40.64)
		)
		(stroke
			(width 0)
			(type default)
		)
	)
	(wire
		(pts
			(xy 365.76 115.57) (xy 382.27 115.57)
		)
		(stroke
			(width 0)
			(type default)
		)
	)
	(wire
		(pts
			(xy 106.68 193.04) (xy 110.49 193.04)
		)
		(stroke
			(width 0)
			(type default)
		)
	)
	(wire
		(pts
			(xy 161.29 41.91) (xy 161.29 46.99)
		)
		(stroke
			(width 0)
			(type default)
		)
	)
	(wire
		(pts
			(xy 219.71 101.6) (xy 219.71 109.22)
		)
		(stroke
			(width 0)
			(type default)
		)
	)
	(wire
		(pts
			(xy 161.29 46.99) (xy 170.18 46.99)
		)
		(stroke
			(width 0)
			(type default)
		)
	)
	(wire
		(pts
			(xy 293.37 58.42) (xy 293.37 60.96)
		)
		(stroke
			(width 0)
			(type default)
		)
	)
	(wire
		(pts
			(xy 50.8 66.04) (xy 44.45 66.04)
		)
		(stroke
			(width 0)
			(type default)
		)
	)
	(wire
		(pts
			(xy 274.32 182.88) (xy 299.72 182.88)
		)
		(stroke
			(width 0)
			(type default)
		)
	)
	(wire
		(pts
			(xy 281.94 71.12) (xy 290.83 71.12)
		)
		(stroke
			(width 0)
			(type default)
		)
	)
	(wire
		(pts
			(xy 204.47 109.22) (xy 210.82 109.22)
		)
		(stroke
			(width 0)
			(type default)
		)
	)
	(wire
		(pts
			(xy 219.71 109.22) (xy 219.71 113.03)
		)
		(stroke
			(width 0)
			(type default)
		)
	)
	(wire
		(pts
			(xy 289.56 138.43) (xy 289.56 139.7)
		)
		(stroke
			(width 0)
			(type default)
		)
	)
	(wire
		(pts
			(xy 105.41 46.99) (xy 135.89 46.99)
		)
		(stroke
			(width 0)
			(type default)
		)
	)
	(wire
		(pts
			(xy 289.56 116.84) (xy 289.56 118.11)
		)
		(stroke
			(width 0)
			(type default)
		)
	)
	(wire
		(pts
			(xy 218.44 198.12) (xy 218.44 208.28)
		)
		(stroke
			(width 0)
			(type default)
		)
	)
	(wire
		(pts
			(xy 78.74 104.14) (xy 78.74 115.57)
		)
		(stroke
			(width 0)
			(type default)
		)
	)
	(wire
		(pts
			(xy 287.02 58.42) (xy 290.83 58.42)
		)
		(stroke
			(width 0)
			(type default)
		)
	)
	(wire
		(pts
			(xy 229.87 153.67) (xy 241.3 153.67)
		)
		(stroke
			(width 0)
			(type default)
		)
	)
	(wire
		(pts
			(xy 236.22 134.62) (xy 241.3 134.62)
		)
		(stroke
			(width 0)
			(type default)
		)
	)
	(wire
		(pts
			(xy 293.37 161.29) (xy 294.64 161.29)
		)
		(stroke
			(width 0)
			(type default)
		)
	)
	(wire
		(pts
			(xy 295.91 204.47) (xy 299.72 204.47)
		)
		(stroke
			(width 0)
			(type default)
		)
	)
	(wire
		(pts
			(xy 208.28 198.12) (xy 205.74 198.12)
		)
		(stroke
			(width 0)
			(type default)
		)
	)
	(wire
		(pts
			(xy 44.45 68.58) (xy 44.45 73.66)
		)
		(stroke
			(width 0)
			(type default)
		)
	)
	(wire
		(pts
			(xy 288.29 151.13) (xy 287.02 151.13)
		)
		(stroke
			(width 0)
			(type default)
		)
	)
	(wire
		(pts
			(xy 71.12 210.82) (xy 68.58 210.82)
		)
		(stroke
			(width 0)
			(type default)
		)
	)
	(wire
		(pts
			(xy 274.32 132.08) (xy 290.83 132.08)
		)
		(stroke
			(width 0)
			(type default)
		)
	)
	(wire
		(pts
			(xy 74.93 82.55) (xy 74.93 95.25)
		)
		(stroke
			(width 0)
			(type default)
		)
	)
	(wire
		(pts
			(xy 287.02 191.77) (xy 287.02 204.47)
		)
		(stroke
			(width 0)
			(type default)
		)
	)
	(wire
		(pts
			(xy 106.68 185.42) (xy 110.49 185.42)
		)
		(stroke
			(width 0)
			(type default)
		)
	)
	(wire
		(pts
			(xy 35.56 83.82) (xy 35.56 93.98)
		)
		(stroke
			(width 0)
			(type default)
		)
	)
	(wire
		(pts
			(xy 63.5 46.99) (xy 63.5 62.23)
		)
		(stroke
			(width 0)
			(type default)
		)
	)
	(wire
		(pts
			(xy 300.99 109.22) (xy 300.99 111.76)
		)
		(stroke
			(width 0)
			(type default)
		)
	)
	(wire
		(pts
			(xy 35.56 73.66) (xy 35.56 83.82)
		)
		(stroke
			(width 0)
			(type default)
		)
	)
	(wire
		(pts
			(xy 300.99 109.22) (xy 289.56 109.22)
		)
		(stroke
			(width 0)
			(type default)
		)
	)
	(wire
		(pts
			(xy 287.02 53.34) (xy 316.23 53.34)
		)
		(stroke
			(width 0)
			(type default)
		)
	)
	(wire
		(pts
			(xy 45.72 83.82) (xy 50.8 83.82)
		)
		(stroke
			(width 0)
			(type default)
		)
	)
	(wire
		(pts
			(xy 59.69 46.99) (xy 63.5 46.99)
		)
		(stroke
			(width 0)
			(type default)
		)
	)
	(wire
		(pts
			(xy 50.8 104.14) (xy 50.8 106.68)
		)
		(stroke
			(width 0)
			(type default)
		)
	)
	(wire
		(pts
			(xy 46.99 48.26) (xy 46.99 53.34)
		)
		(stroke
			(width 0)
			(type default)
		)
	)
	(wire
		(pts
			(xy 360.68 165.1) (xy 365.76 165.1)
		)
		(stroke
			(width 0)
			(type default)
		)
	)
	(polyline
		(pts
			(xy 186.69 231.14) (xy 320.04 231.14)
		)
		(stroke
			(width 0)
			(type dash)
		)
	)
	(wire
		(pts
			(xy 293.37 163.83) (xy 294.64 163.83)
		)
		(stroke
			(width 0)
			(type default)
		)
	)
	(wire
		(pts
			(xy 229.87 181.61) (xy 241.3 181.61)
		)
		(stroke
			(width 0)
			(type default)
		)
	)
	(wire
		(pts
			(xy 289.56 144.78) (xy 289.56 146.05)
		)
		(stroke
			(width 0)
			(type default)
		)
	)
	(wire
		(pts
			(xy 353.06 231.14) (xy 353.06 233.68)
		)
		(stroke
			(width 0)
			(type default)
		)
	)
	(wire
		(pts
			(xy 233.68 129.54) (xy 233.68 137.16)
		)
		(stroke
			(width 0)
			(type default)
		)
	)
	(wire
		(pts
			(xy 233.68 143.51) (xy 241.3 143.51)
		)
		(stroke
			(width 0)
			(type default)
		)
	)
	(wire
		(pts
			(xy 96.52 200.66) (xy 101.6 200.66)
		)
		(stroke
			(width 0)
			(type default)
		)
	)
	(wire
		(pts
			(xy 261.62 55.88) (xy 266.7 55.88)
		)
		(stroke
			(width 0)
			(type default)
		)
	)
	(wire
		(pts
			(xy 96.52 193.04) (xy 101.6 193.04)
		)
		(stroke
			(width 0)
			(type default)
		)
	)
	(wire
		(pts
			(xy 306.07 144.78) (xy 306.07 146.05)
		)
		(stroke
			(width 0)
			(type default)
		)
	)
	(wire
		(pts
			(xy 382.27 115.57) (xy 382.27 116.84)
		)
		(stroke
			(width 0)
			(type default)
		)
	)
	(wire
		(pts
			(xy 147.32 265.43) (xy 151.13 265.43)
		)
		(stroke
			(width 0)
			(type default)
		)
	)
	(wire
		(pts
			(xy 293.37 66.04) (xy 293.37 71.12)
		)
		(stroke
			(width 0)
			(type default)
		)
	)
	(wire
		(pts
			(xy 340.36 218.44) (xy 345.44 218.44)
		)
		(stroke
			(width 0)
			(type default)
		)
	)
	(wire
		(pts
			(xy 299.72 146.05) (xy 306.07 146.05)
		)
		(stroke
			(width 0)
			(type default)
		)
	)
	(wire
		(pts
			(xy 375.92 153.67) (xy 378.46 153.67)
		)
		(stroke
			(width 0)
			(type default)
		)
	)
	(wire
		(pts
			(xy 287.02 146.05) (xy 287.02 151.13)
		)
		(stroke
			(width 0)
			(type default)
		)
	)
	(wire
		(pts
			(xy 364.49 223.52) (xy 364.49 234.95)
		)
		(stroke
			(width 0)
			(type default)
		)
	)
	(wire
		(pts
			(xy 219.71 118.11) (xy 219.71 119.38)
		)
		(stroke
			(width 0)
			(type default)
		)
	)
	(wire
		(pts
			(xy 351.79 124.46) (xy 355.6 124.46)
		)
		(stroke
			(width 0)
			(type default)
		)
	)
	(wire
		(pts
			(xy 381 55.88) (xy 391.16 55.88)
		)
		(stroke
			(width 0)
			(type default)
		)
	)
	(wire
		(pts
			(xy 36.83 185.42) (xy 36.83 187.96)
		)
		(stroke
			(width 0)
			(type default)
		)
	)
	(wire
		(pts
			(xy 387.35 153.67) (xy 398.78 153.67)
		)
		(stroke
			(width 0)
			(type default)
		)
	)
	(wire
		(pts
			(xy 306.07 30.48) (xy 306.07 40.64)
		)
		(stroke
			(width 0)
			(type default)
		)
	)
	(wire
		(pts
			(xy 99.06 60.96) (xy 99.06 73.66)
		)
		(stroke
			(width 0)
			(type default)
		)
	)
	(wire
		(pts
			(xy 316.23 53.34) (xy 316.23 55.88)
		)
		(stroke
			(width 0)
			(type default)
		)
	)
	(wire
		(pts
			(xy 240.03 186.69) (xy 240.03 184.15)
		)
		(stroke
			(width 0)
			(type default)
		)
	)
	(wire
		(pts
			(xy 44.45 40.64) (xy 57.15 40.64)
		)
		(stroke
			(width 0)
			(type default)
		)
	)
	(wire
		(pts
			(xy 251.46 109.22) (xy 251.46 111.76)
		)
		(stroke
			(width 0)
			(type default)
		)
	)
	(wire
		(pts
			(xy 68.58 218.44) (xy 68.58 222.25)
		)
		(stroke
			(width 0)
			(type default)
		)
	)
	(wire
		(pts
			(xy 50.8 66.04) (xy 50.8 83.82)
		)
		(stroke
			(width 0)
			(type default)
		)
	)
	(wire
		(pts
			(xy 106.68 195.58) (xy 110.49 195.58)
		)
		(stroke
			(width 0)
			(type default)
		)
	)
	(polyline
		(pts
			(xy 12.7 132.08) (xy 137.16 132.08)
		)
		(stroke
			(width 0)
			(type dash)
		)
	)
	(wire
		(pts
			(xy 364.49 223.52) (xy 356.87 223.52)
		)
		(stroke
			(width 0)
			(type default)
		)
	)
	(wire
		(pts
			(xy 287.02 157.48) (xy 299.72 157.48)
		)
		(stroke
			(width 0)
			(type default)
		)
	)
	(wire
		(pts
			(xy 387.35 153.67) (xy 387.35 154.94)
		)
		(stroke
			(width 0)
			(type default)
		)
	)
	(wire
		(pts
			(xy 306.07 137.16) (xy 306.07 139.7)
		)
		(stroke
			(width 0)
			(type default)
		)
	)
	(wire
		(pts
			(xy 140.97 182.88) (xy 143.51 182.88)
		)
		(stroke
			(width 0)
			(type default)
		)
	)
	(wire
		(pts
			(xy 200.66 137.16) (xy 200.66 138.43)
		)
		(stroke
			(width 0)
			(type default)
		)
	)
	(wire
		(pts
			(xy 316.23 45.72) (xy 316.23 53.34)
		)
		(stroke
			(width 0)
			(type default)
		)
	)
	(wire
		(pts
			(xy 336.55 170.18) (xy 365.76 170.18)
		)
		(stroke
			(width 0)
			(type default)
		)
	)
	(wire
		(pts
			(xy 299.72 212.09) (xy 299.72 217.17)
		)
		(stroke
			(width 0)
			(type default)
		)
	)
	(wire
		(pts
			(xy 227.33 256.54) (xy 236.22 256.54)
		)
		(stroke
			(width 0)
			(type default)
		)
	)
	(wire
		(pts
			(xy 68.58 215.9) (xy 68.58 218.44)
		)
		(stroke
			(width 0)
			(type default)
		)
	)
	(wire
		(pts
			(xy 204.47 109.22) (xy 193.04 109.22)
		)
		(stroke
			(width 0)
			(type default)
		)
	)
	(polyline
		(pts
			(xy 320.04 251.46) (xy 320.04 86.36)
		)
		(stroke
			(width 0)
			(type dash)
		)
	)
	(wire
		(pts
			(xy 67.31 182.88) (xy 71.12 182.88)
		)
		(stroke
			(width 0)
			(type default)
		)
	)
	(wire
		(pts
			(xy 218.44 139.7) (xy 215.9 139.7)
		)
		(stroke
			(width 0)
			(type default)
		)
	)
	(wire
		(pts
			(xy 306.07 152.4) (xy 306.07 153.67)
		)
		(stroke
			(width 0)
			(type default)
		)
	)
	(wire
		(pts
			(xy 203.2 251.46) (xy 208.28 251.46)
		)
		(stroke
			(width 0)
			(type default)
		)
	)
	(wire
		(pts
			(xy 68.58 218.44) (xy 71.12 218.44)
		)
		(stroke
			(width 0)
			(type default)
		)
	)
	(wire
		(pts
			(xy 287.02 146.05) (xy 289.56 146.05)
		)
		(stroke
			(width 0)
			(type default)
		)
	)
	(wire
		(pts
			(xy 240.03 187.96) (xy 240.03 190.5)
		)
		(stroke
			(width 0)
			(type default)
		)
	)
	(wire
		(pts
			(xy 229.87 184.15) (xy 232.41 184.15)
		)
		(stroke
			(width 0)
			(type default)
		)
	)
	(wire
		(pts
			(xy 290.83 71.12) (xy 293.37 71.12)
		)
		(stroke
			(width 0)
			(type default)
		)
	)
	(wire
		(pts
			(xy 149.86 46.99) (xy 161.29 46.99)
		)
		(stroke
			(width 0)
			(type default)
		)
	)
	(wire
		(pts
			(xy 375.92 177.8) (xy 375.92 179.07)
		)
		(stroke
			(width 0)
			(type default)
		)
	)
	(wire
		(pts
			(xy 375.92 153.67) (xy 363.22 153.67)
		)
		(stroke
			(width 0)
			(type default)
		)
	)
	(wire
		(pts
			(xy 60.96 187.96) (xy 71.12 187.96)
		)
		(stroke
			(width 0)
			(type default)
		)
	)
	(wire
		(pts
			(xy 193.04 109.22) (xy 193.04 113.03)
		)
		(stroke
			(width 0)
			(type default)
		)
	)
	(wire
		(pts
			(xy 240.03 190.5) (xy 240.03 194.31)
		)
		(stroke
			(width 0)
			(type default)
		)
	)
	(wire
		(pts
			(xy 342.9 220.98) (xy 373.38 220.98)
		)
		(stroke
			(width 0)
			(type default)
		)
	)
	(wire
		(pts
			(xy 299.72 146.05) (xy 299.72 157.48)
		)
		(stroke
			(width 0)
			(type default)
		)
	)
	(wire
		(pts
			(xy 342.9 220.98) (xy 342.9 224.79)
		)
		(stroke
			(width 0)
			(type default)
		)
	)
	(wire
		(pts
			(xy 370.84 226.06) (xy 370.84 228.6)
		)
		(stroke
			(width 0)
			(type default)
		)
	)
	(wire
		(pts
			(xy 60.96 190.5) (xy 71.12 190.5)
		)
		(stroke
			(width 0)
			(type default)
		)
	)
	(wire
		(pts
			(xy 135.89 68.58) (xy 135.89 73.66)
		)
		(stroke
			(width 0)
			(type default)
		)
	)
	(wire
		(pts
			(xy 185.42 46.99) (xy 199.39 46.99)
		)
		(stroke
			(width 0)
			(type default)
		)
	)
	(wire
		(pts
			(xy 208.28 251.46) (xy 208.28 257.81)
		)
		(stroke
			(width 0)
			(type default)
		)
	)
	(wire
		(pts
			(xy 332.74 231.14) (xy 332.74 223.52)
		)
		(stroke
			(width 0)
			(type default)
		)
	)
	(wire
		(pts
			(xy 130.81 193.04) (xy 130.81 182.88)
		)
		(stroke
			(width 0)
			(type default)
		)
	)
	(wire
		(pts
			(xy 74.93 95.25) (xy 74.93 99.06)
		)
		(stroke
			(width 0)
			(type default)
		)
	)
	(wire
		(pts
			(xy 93.98 95.25) (xy 74.93 95.25)
		)
		(stroke
			(width 0)
			(type default)
		)
	)
	(wire
		(pts
			(xy 36.83 177.8) (xy 36.83 180.34)
		)
		(stroke
			(width 0)
			(type default)
		)
	)
	(wire
		(pts
			(xy 135.89 57.15) (xy 135.89 63.5)
		)
		(stroke
			(width 0)
			(type default)
		)
	)
	(wire
		(pts
			(xy 68.58 210.82) (xy 68.58 213.36)
		)
		(stroke
			(width 0)
			(type default)
		)
	)
	(wire
		(pts
			(xy 36.83 176.53) (xy 36.83 177.8)
		)
		(stroke
			(width 0)
			(type default)
		)
	)
	(wire
		(pts
			(xy 306.07 60.96) (xy 306.07 63.5)
		)
		(stroke
			(width 0)
			(type default)
		)
	)
	(wire
		(pts
			(xy 353.06 238.76) (xy 353.06 240.03)
		)
		(stroke
			(width 0)
			(type default)
		)
	)
	(wire
		(pts
			(xy 289.56 109.22) (xy 276.86 109.22)
		)
		(stroke
			(width 0)
			(type default)
		)
	)
	(wire
		(pts
			(xy 149.86 66.04) (xy 149.86 73.66)
		)
		(stroke
			(width 0)
			(type default)
		)
	)
	(wire
		(pts
			(xy 161.29 66.04) (xy 161.29 73.66)
		)
		(stroke
			(width 0)
			(type default)
		)
	)
	(wire
		(pts
			(xy 276.86 30.48) (xy 276.86 33.02)
		)
		(stroke
			(width 0)
			(type default)
		)
	)
	(wire
		(pts
			(xy 287.02 204.47) (xy 287.02 207.01)
		)
		(stroke
			(width 0)
			(type default)
		)
	)
	(wire
		(pts
			(xy 106.68 200.66) (xy 110.49 200.66)
		)
		(stroke
			(width 0)
			(type default)
		)
	)
	(wire
		(pts
			(xy 147.32 247.65) (xy 151.13 247.65)
		)
		(stroke
			(width 0)
			(type default)
		)
	)
	(wire
		(pts
			(xy 381 45.72) (xy 381 55.88)
		)
		(stroke
			(width 0)
			(type default)
		)
	)
	(wire
		(pts
			(xy 48.26 50.8) (xy 114.3 50.8)
		)
		(stroke
			(width 0)
			(type default)
		)
	)
	(wire
		(pts
			(xy 241.3 158.75) (xy 210.82 158.75)
		)
		(stroke
			(width 0)
			(type default)
		)
	)
	(wire
		(pts
			(xy 227.33 256.54) (xy 219.71 256.54)
		)
		(stroke
			(width 0)
			(type default)
		)
	)
	(wire
		(pts
			(xy 237.49 186.69) (xy 240.03 186.69)
		)
		(stroke
			(width 0)
			(type default)
		)
	)
	(wire
		(pts
			(xy 147.32 251.46) (xy 151.13 251.46)
		)
		(stroke
			(width 0)
			(type default)
		)
	)
	(wire
		(pts
			(xy 215.9 198.12) (xy 218.44 198.12)
		)
		(stroke
			(width 0)
			(type default)
		)
	)
	(wire
		(pts
			(xy 44.45 48.26) (xy 46.99 48.26)
		)
		(stroke
			(width 0)
			(type default)
		)
	)
	(wire
		(pts
			(xy 340.36 220.98) (xy 342.9 220.98)
		)
		(stroke
			(width 0)
			(type default)
		)
	)
	(wire
		(pts
			(xy 276.86 109.22) (xy 264.16 109.22)
		)
		(stroke
			(width 0)
			(type default)
		)
	)
	(wire
		(pts
			(xy 35.56 93.98) (xy 35.56 104.14)
		)
		(stroke
			(width 0)
			(type default)
		)
	)
	(wire
		(pts
			(xy 133.35 190.5) (xy 133.35 180.34)
		)
		(stroke
			(width 0)
			(type default)
		)
	)
	(wire
		(pts
			(xy 205.74 215.9) (xy 205.74 222.25)
		)
		(stroke
			(width 0)
			(type default)
		)
	)
	(wire
		(pts
			(xy 356.87 231.14) (xy 353.06 231.14)
		)
		(stroke
			(width 0)
			(type default)
		)
	)
	(wire
		(pts
			(xy 287.02 204.47) (xy 290.83 204.47)
		)
		(stroke
			(width 0)
			(type default)
		)
	)
	(wire
		(pts
			(xy 147.32 256.54) (xy 151.13 256.54)
		)
		(stroke
			(width 0)
			(type default)
		)
	)
	(wire
		(pts
			(xy 287.02 191.77) (xy 289.56 191.77)
		)
		(stroke
			(width 0)
			(type default)
		)
	)
	(wire
		(pts
			(xy 96.52 187.96) (xy 101.6 187.96)
		)
		(stroke
			(width 0)
			(type default)
		)
	)
	(wire
		(pts
			(xy 336.55 170.18) (xy 336.55 173.99)
		)
		(stroke
			(width 0)
			(type default)
		)
	)
	(wire
		(pts
			(xy 195.58 146.05) (xy 200.66 146.05)
		)
		(stroke
			(width 0)
			(type default)
		)
	)
	(wire
		(pts
			(xy 96.52 180.34) (xy 133.35 180.34)
		)
		(stroke
			(width 0)
			(type default)
		)
	)
	(wire
		(pts
			(xy 147.32 242.57) (xy 151.13 242.57)
		)
		(stroke
			(width 0)
			(type default)
		)
	)
	(wire
		(pts
			(xy 375.92 153.67) (xy 375.92 160.02)
		)
		(stroke
			(width 0)
			(type default)
		)
	)
	(wire
		(pts
			(xy 363.22 172.72) (xy 365.76 172.72)
		)
		(stroke
			(width 0)
			(type default)
		)
	)
	(wire
		(pts
			(xy 208.28 251.46) (xy 236.22 251.46)
		)
		(stroke
			(width 0)
			(type default)
		)
	)
	(wire
		(pts
			(xy 45.72 180.34) (xy 45.72 177.8)
		)
		(stroke
			(width 0)
			(type default)
		)
	)
	(wire
		(pts
			(xy 68.58 163.83) (xy 101.6 163.83)
		)
		(stroke
			(width 0)
			(type default)
		)
	)
	(wire
		(pts
			(xy 96.52 203.2) (xy 101.6 203.2)
		)
		(stroke
			(width 0)
			(type default)
		)
	)
	(wire
		(pts
			(xy 316.23 30.48) (xy 316.23 40.64)
		)
		(stroke
			(width 0)
			(type default)
		)
	)
	(wire
		(pts
			(xy 276.86 33.02) (xy 276.86 43.18)
		)
		(stroke
			(width 0)
			(type default)
		)
	)
	(wire
		(pts
			(xy 364.49 223.52) (xy 373.38 223.52)
		)
		(stroke
			(width 0)
			(type default)
		)
	)
	(wire
		(pts
			(xy 236.22 259.08) (xy 233.68 259.08)
		)
		(stroke
			(width 0)
			(type default)
		)
	)
	(wire
		(pts
			(xy 147.32 260.35) (xy 151.13 260.35)
		)
		(stroke
			(width 0)
			(type default)
		)
	)
	(wire
		(pts
			(xy 68.58 215.9) (xy 71.12 215.9)
		)
		(stroke
			(width 0)
			(type default)
		)
	)
	(wire
		(pts
			(xy 135.89 52.07) (xy 135.89 46.99)
		)
		(stroke
			(width 0)
			(type default)
		)
	)
	(wire
		(pts
			(xy 238.76 132.08) (xy 241.3 132.08)
		)
		(stroke
			(width 0)
			(type default)
		)
	)
	(wire
		(pts
			(xy 276.86 33.02) (xy 260.35 33.02)
		)
		(stroke
			(width 0)
			(type default)
		)
	)
	(wire
		(pts
			(xy 276.86 109.22) (xy 276.86 111.76)
		)
		(stroke
			(width 0)
			(type default)
		)
	)
	(wire
		(pts
			(xy 93.98 114.3) (xy 93.98 115.57)
		)
		(stroke
			(width 0)
			(type default)
		)
	)
	(wire
		(pts
			(xy 264.16 109.22) (xy 251.46 109.22)
		)
		(stroke
			(width 0)
			(type default)
		)
	)
	(wire
		(pts
			(xy 290.83 58.42) (xy 290.83 71.12)
		)
		(stroke
			(width 0)
			(type default)
		)
	)
	(wire
		(pts
			(xy 351.79 129.54) (xy 355.6 129.54)
		)
		(stroke
			(width 0)
			(type default)
		)
	)
	(wire
		(pts
			(xy 101.6 163.83) (xy 107.95 163.83)
		)
		(stroke
			(width 0)
			(type default)
		)
	)
	(wire
		(pts
			(xy 229.87 179.07) (xy 241.3 179.07)
		)
		(stroke
			(width 0)
			(type default)
		)
	)
	(wire
		(pts
			(xy 287.02 50.8) (xy 306.07 50.8)
		)
		(stroke
			(width 0)
			(type default)
		)
	)
	(wire
		(pts
			(xy 50.8 93.98) (xy 50.8 104.14)
		)
		(stroke
			(width 0)
			(type default)
		)
	)
	(wire
		(pts
			(xy 204.47 109.22) (xy 204.47 113.03)
		)
		(stroke
			(width 0)
			(type default)
		)
	)
	(wire
		(pts
			(xy 118.11 170.18) (xy 118.11 171.45)
		)
		(stroke
			(width 0)
			(type default)
		)
	)
	(wire
		(pts
			(xy 193.04 118.11) (xy 193.04 119.38)
		)
		(stroke
			(width 0)
			(type default)
		)
	)
	(wire
		(pts
			(xy 231.14 109.22) (xy 236.22 109.22)
		)
		(stroke
			(width 0)
			(type default)
		)
	)
	(wire
		(pts
			(xy 274.32 185.42) (xy 287.02 185.42)
		)
		(stroke
			(width 0)
			(type default)
		)
	)
	(wire
		(pts
			(xy 59.69 46.99) (xy 59.69 68.58)
		)
		(stroke
			(width 0)
			(type default)
		)
	)
	(wire
		(pts
			(xy 231.14 109.22) (xy 231.14 113.03)
		)
		(stroke
			(width 0)
			(type default)
		)
	)
	(wire
		(pts
			(xy 106.68 198.12) (xy 110.49 198.12)
		)
		(stroke
			(width 0)
			(type default)
		)
	)
	(wire
		(pts
			(xy 63.5 46.99) (xy 87.63 46.99)
		)
		(stroke
			(width 0)
			(type default)
		)
	)
	(wire
		(pts
			(xy 306.07 146.05) (xy 311.15 146.05)
		)
		(stroke
			(width 0)
			(type default)
		)
	)
	(wire
		(pts
			(xy 140.97 190.5) (xy 142.24 190.5)
		)
		(stroke
			(width 0)
			(type default)
		)
	)
	(wire
		(pts
			(xy 228.6 186.69) (xy 232.41 186.69)
		)
		(stroke
			(width 0)
			(type default)
		)
	)
	(wire
		(pts
			(xy 68.58 213.36) (xy 68.58 215.9)
		)
		(stroke
			(width 0)
			(type default)
		)
	)
	(wire
		(pts
			(xy 99.06 91.44) (xy 99.06 100.33)
		)
		(stroke
			(width 0)
			(type default)
		)
	)
	(wire
		(pts
			(xy 264.16 109.22) (xy 264.16 111.76)
		)
		(stroke
			(width 0)
			(type default)
		)
	)
	(wire
		(pts
			(xy 233.68 259.08) (xy 233.68 261.62)
		)
		(stroke
			(width 0)
			(type default)
		)
	)
	(wire
		(pts
			(xy 140.97 180.34) (xy 143.51 180.34)
		)
		(stroke
			(width 0)
			(type default)
		)
	)
	(wire
		(pts
			(xy 205.74 254) (xy 236.22 254)
		)
		(stroke
			(width 0)
			(type default)
		)
	)
	(wire
		(pts
			(xy 205.74 208.28) (xy 209.55 208.28)
		)
		(stroke
			(width 0)
			(type default)
		)
	)
	(wire
		(pts
			(xy 96.52 185.42) (xy 101.6 185.42)
		)
		(stroke
			(width 0)
			(type default)
		)
	)
	(wire
		(pts
			(xy 214.63 208.28) (xy 218.44 208.28)
		)
		(stroke
			(width 0)
			(type default)
		)
	)
	(wire
		(pts
			(xy 306.07 45.72) (xy 306.07 50.8)
		)
		(stroke
			(width 0)
			(type default)
		)
	)
	(wire
		(pts
			(xy 203.2 256.54) (xy 203.2 257.81)
		)
		(stroke
			(width 0)
			(type default)
		)
	)
	(wire
		(pts
			(xy 74.93 104.14) (xy 74.93 115.57)
		)
		(stroke
			(width 0)
			(type default)
		)
	)
	(wire
		(pts
			(xy 306.07 50.8) (xy 306.07 55.88)
		)
		(stroke
			(width 0)
			(type default)
		)
	)
	(wire
		(pts
			(xy 293.37 196.85) (xy 293.37 198.12)
		)
		(stroke
			(width 0)
			(type default)
		)
	)
	(wire
		(pts
			(xy 353.06 229.87) (xy 353.06 231.14)
		)
		(stroke
			(width 0)
			(type default)
		)
	)
	(wire
		(pts
			(xy 35.56 73.66) (xy 44.45 73.66)
		)
		(stroke
			(width 0)
			(type default)
		)
	)
	(wire
		(pts
			(xy 71.12 213.36) (xy 68.58 213.36)
		)
		(stroke
			(width 0)
			(type default)
		)
	)
	(wire
		(pts
			(xy 238.76 109.22) (xy 238.76 132.08)
		)
		(stroke
			(width 0)
			(type default)
		)
	)
	(wire
		(pts
			(xy 300.99 116.84) (xy 300.99 118.11)
		)
		(stroke
			(width 0)
			(type default)
		)
	)
	(wire
		(pts
			(xy 210.82 166.37) (xy 210.82 173.99)
		)
		(stroke
			(width 0)
			(type default)
		)
	)
	(polyline
		(pts
			(xy 186.69 132.08) (xy 186.69 284.48)
		)
		(stroke
			(width 0)
			(type dash)
		)
	)
	(wire
		(pts
			(xy 219.71 256.54) (xy 219.71 264.16)
		)
		(stroke
			(width 0)
			(type default)
		)
	)
	(wire
		(pts
			(xy 360.68 167.64) (xy 365.76 167.64)
		)
		(stroke
			(width 0)
			(type default)
		)
	)
	(wire
		(pts
			(xy 274.32 137.16) (xy 287.02 137.16)
		)
		(stroke
			(width 0)
			(type default)
		)
	)
	(wire
		(pts
			(xy 289.56 111.76) (xy 289.56 109.22)
		)
		(stroke
			(width 0)
			(type default)
		)
	)
	(wire
		(pts
			(xy 106.68 203.2) (xy 134.62 203.2)
		)
		(stroke
			(width 0)
			(type default)
		)
	)
	(wire
		(pts
			(xy 299.72 191.77) (xy 299.72 204.47)
		)
		(stroke
			(width 0)
			(type default)
		)
	)
	(polyline
		(pts
			(xy 243.84 12.7) (xy 243.84 86.36)
		)
		(stroke
			(width 0)
			(type dash)
		)
	)
	(wire
		(pts
			(xy 215.9 271.78) (xy 215.9 273.05)
		)
		(stroke
			(width 0)
			(type default)
		)
	)
	(wire
		(pts
			(xy 140.97 193.04) (xy 142.24 193.04)
		)
		(stroke
			(width 0)
			(type default)
		)
	)
	(wire
		(pts
			(xy 264.16 102.87) (xy 264.16 109.22)
		)
		(stroke
			(width 0)
			(type default)
		)
	)
	(wire
		(pts
			(xy 111.76 53.34) (xy 127 53.34)
		)
		(stroke
			(width 0)
			(type default)
		)
	)
	(wire
		(pts
			(xy 215.9 262.89) (xy 215.9 264.16)
		)
		(stroke
			(width 0)
			(type default)
		)
	)
	(wire
		(pts
			(xy 199.39 55.88) (xy 199.39 59.69)
		)
		(stroke
			(width 0)
			(type default)
		)
	)
	(wire
		(pts
			(xy 93.98 95.25) (xy 93.98 109.22)
		)
		(stroke
			(width 0)
			(type default)
		)
	)
	(wire
		(pts
			(xy 130.81 182.88) (xy 135.89 182.88)
		)
		(stroke
			(width 0)
			(type default)
		)
	)
	(wire
		(pts
			(xy 297.18 191.77) (xy 299.72 191.77)
		)
		(stroke
			(width 0)
			(type default)
		)
	)
	(polyline
		(pts
			(xy 137.16 86.36) (xy 406.4 86.36)
		)
		(stroke
			(width 0)
			(type dash)
		)
	)
	(wire
		(pts
			(xy 231.14 118.11) (xy 231.14 119.38)
		)
		(stroke
			(width 0)
			(type default)
		)
	)
	(wire
		(pts
			(xy 345.44 218.44) (xy 373.38 218.44)
		)
		(stroke
			(width 0)
			(type default)
		)
	)
	(wire
		(pts
			(xy 365.76 113.03) (xy 365.76 115.57)
		)
		(stroke
			(width 0)
			(type default)
		)
	)
	(wire
		(pts
			(xy 46.99 53.34) (xy 111.76 53.34)
		)
		(stroke
			(width 0)
			(type default)
		)
	)
	(wire
		(pts
			(xy 68.58 180.34) (xy 68.58 163.83)
		)
		(stroke
			(width 0)
			(type default)
		)
	)
	(wire
		(pts
			(xy 45.72 177.8) (xy 71.12 177.8)
		)
		(stroke
			(width 0)
			(type default)
		)
	)
	(wire
		(pts
			(xy 387.35 160.02) (xy 387.35 161.29)
		)
		(stroke
			(width 0)
			(type default)
		)
	)
	(wire
		(pts
			(xy 101.6 163.83) (xy 101.6 177.8)
		)
		(stroke
			(width 0)
			(type default)
		)
	)
	(wire
		(pts
			(xy 240.03 184.15) (xy 241.3 184.15)
		)
		(stroke
			(width 0)
			(type default)
		)
	)
	(wire
		(pts
			(xy 62.23 182.88) (xy 58.42 182.88)
		)
		(stroke
			(width 0)
			(type default)
		)
	)
	(wire
		(pts
			(xy 274.32 168.91) (xy 284.48 168.91)
		)
		(stroke
			(width 0)
			(type default)
		)
	)
	(wire
		(pts
			(xy 237.49 184.15) (xy 240.03 184.15)
		)
		(stroke
			(width 0)
			(type default)
		)
	)
	(wire
		(pts
			(xy 238.76 109.22) (xy 251.46 109.22)
		)
		(stroke
			(width 0)
			(type default)
		)
	)
	(wire
		(pts
			(xy 205.74 254) (xy 205.74 257.81)
		)
		(stroke
			(width 0)
			(type default)
		)
	)
	(wire
		(pts
			(xy 44.45 38.1) (xy 57.15 38.1)
		)
		(stroke
			(width 0)
			(type default)
		)
	)
	(wire
		(pts
			(xy 149.86 41.91) (xy 149.86 46.99)
		)
		(stroke
			(width 0)
			(type default)
		)
	)
	(wire
		(pts
			(xy 63.5 76.2) (xy 63.5 67.31)
		)
		(stroke
			(width 0)
			(type default)
		)
	)
	(wire
		(pts
			(xy 195.58 264.16) (xy 195.58 256.54)
		)
		(stroke
			(width 0)
			(type default)
		)
	)
	(wire
		(pts
			(xy 363.22 153.67) (xy 363.22 172.72)
		)
		(stroke
			(width 0)
			(type default)
		)
	)
	(wire
		(pts
			(xy 336.55 156.21) (xy 336.55 161.29)
		)
		(stroke
			(width 0)
			(type default)
		)
	)
	(wire
		(pts
			(xy 48.26 45.72) (xy 48.26 50.8)
		)
		(stroke
			(width 0)
			(type default)
		)
	)
	(wire
		(pts
			(xy 276.86 116.84) (xy 276.86 118.11)
		)
		(stroke
			(width 0)
			(type default)
		)
	)
	(wire
		(pts
			(xy 200.66 143.51) (xy 200.66 146.05)
		)
		(stroke
			(width 0)
			(type default)
		)
	)
	(wire
		(pts
			(xy 35.56 104.14) (xy 35.56 106.68)
		)
		(stroke
			(width 0)
			(type default)
		)
	)
	(wire
		(pts
			(xy 378.46 153.67) (xy 378.46 160.02)
		)
		(stroke
			(width 0)
			(type default)
		)
	)
	(wire
		(pts
			(xy 287.02 151.13) (xy 274.32 151.13)
		)
		(stroke
			(width 0)
			(type default)
		)
	)
	(wire
		(pts
			(xy 107.95 163.83) (xy 107.95 165.1)
		)
		(stroke
			(width 0)
			(type default)
		)
	)
	(wire
		(pts
			(xy 332.74 223.52) (xy 340.36 223.52)
		)
		(stroke
			(width 0)
			(type default)
		)
	)
	(wire
		(pts
			(xy 35.56 83.82) (xy 40.64 83.82)
		)
		(stroke
			(width 0)
			(type default)
		)
	)
	(wire
		(pts
			(xy 45.72 185.42) (xy 45.72 187.96)
		)
		(stroke
			(width 0)
			(type default)
		)
	)
	(wire
		(pts
			(xy 236.22 109.22) (xy 236.22 134.62)
		)
		(stroke
			(width 0)
			(type default)
		)
	)
	(wire
		(pts
			(xy 149.86 46.99) (xy 149.86 60.96)
		)
		(stroke
			(width 0)
			(type default)
		)
	)
	(wire
		(pts
			(xy 274.32 134.62) (xy 285.75 134.62)
		)
		(stroke
			(width 0)
			(type default)
		)
	)
	(wire
		(pts
			(xy 287.02 212.09) (xy 287.02 217.17)
		)
		(stroke
			(width 0)
			(type default)
		)
	)
	(wire
		(pts
			(xy 35.56 93.98) (xy 40.64 93.98)
		)
		(stroke
			(width 0)
			(type default)
		)
	)
	(wire
		(pts
			(xy 237.49 168.91) (xy 241.3 168.91)
		)
		(stroke
			(width 0)
			(type default)
		)
	)
	(wire
		(pts
			(xy 274.32 161.29) (xy 287.02 161.29)
		)
		(stroke
			(width 0)
			(type default)
		)
	)
	(wire
		(pts
			(xy 96.52 195.58) (xy 101.6 195.58)
		)
		(stroke
			(width 0)
			(type default)
		)
	)
	(wire
		(pts
			(xy 274.32 163.83) (xy 288.29 163.83)
		)
		(stroke
			(width 0)
			(type default)
		)
	)
	(wire
		(pts
			(xy 288.29 148.59) (xy 274.32 148.59)
		)
		(stroke
			(width 0)
			(type default)
		)
	)
	(wire
		(pts
			(xy 44.45 33.02) (xy 63.5 33.02)
		)
		(stroke
			(width 0)
			(type default)
		)
	)
	(wire
		(pts
			(xy 44.45 53.34) (xy 46.99 53.34)
		)
		(stroke
			(width 0)
			(type default)
		)
	)
	(wire
		(pts
			(xy 261.62 50.8) (xy 266.7 50.8)
		)
		(stroke
			(width 0)
			(type default)
		)
	)
	(wire
		(pts
			(xy 87.63 64.77) (xy 87.63 73.66)
		)
		(stroke
			(width 0)
			(type default)
		)
	)
	(wire
		(pts
			(xy 199.39 46.99) (xy 199.39 50.8)
		)
		(stroke
			(width 0)
			(type default)
		)
	)
	(wire
		(pts
			(xy 96.52 182.88) (xy 130.81 182.88)
		)
		(stroke
			(width 0)
			(type default)
		)
	)
	(wire
		(pts
			(xy 111.76 53.34) (xy 111.76 60.96)
		)
		(stroke
			(width 0)
			(type default)
		)
	)
	(wire
		(pts
			(xy 388.62 45.72) (xy 388.62 50.8)
		)
		(stroke
			(width 0)
			(type default)
		)
	)
	(wire
		(pts
			(xy 231.14 109.22) (xy 219.71 109.22)
		)
		(stroke
			(width 0)
			(type default)
		)
	)
	(wire
		(pts
			(xy 229.87 166.37) (xy 232.41 166.37)
		)
		(stroke
			(width 0)
			(type default)
		)
	)
	(wire
		(pts
			(xy 219.71 101.6) (xy 209.55 101.6)
		)
		(stroke
			(width 0)
			(type default)
		)
	)
	(wire
		(pts
			(xy 203.2 254) (xy 205.74 254)
		)
		(stroke
			(width 0)
			(type default)
		)
	)
	(wire
		(pts
			(xy 219.71 101.6) (xy 223.52 101.6)
		)
		(stroke
			(width 0)
			(type default)
		)
	)
	(wire
		(pts
			(xy 227.33 256.54) (xy 227.33 267.97)
		)
		(stroke
			(width 0)
			(type default)
		)
	)
	(wire
		(pts
			(xy 199.39 44.45) (xy 199.39 46.99)
		)
		(stroke
			(width 0)
			(type default)
		)
	)
	(wire
		(pts
			(xy 398.78 153.67) (xy 398.78 154.94)
		)
		(stroke
			(width 0)
			(type default)
		)
	)
	(wire
		(pts
			(xy 378.46 153.67) (xy 387.35 153.67)
		)
		(stroke
			(width 0)
			(type default)
		)
	)
	(wire
		(pts
			(xy 299.72 204.47) (xy 299.72 207.01)
		)
		(stroke
			(width 0)
			(type default)
		)
	)
	(wire
		(pts
			(xy 287.02 161.29) (xy 288.29 161.29)
		)
		(stroke
			(width 0)
			(type default)
		)
	)
	(wire
		(pts
			(xy 375.92 55.88) (xy 381 55.88)
		)
		(stroke
			(width 0)
			(type default)
		)
	)
	(wire
		(pts
			(xy 241.3 101.6) (xy 228.6 101.6)
		)
		(stroke
			(width 0)
			(type default)
		)
	)
	(wire
		(pts
			(xy 161.29 46.99) (xy 161.29 60.96)
		)
		(stroke
			(width 0)
			(type default)
		)
	)
	(wire
		(pts
			(xy 365.76 115.57) (xy 365.76 119.38)
		)
		(stroke
			(width 0)
			(type default)
		)
	)
	(wire
		(pts
			(xy 224.79 31.75) (xy 224.79 34.29)
		)
		(stroke
			(width 0)
			(type default)
		)
	)
	(wire
		(pts
			(xy 240.03 190.5) (xy 241.3 190.5)
		)
		(stroke
			(width 0)
			(type default)
		)
	)
	(wire
		(pts
			(xy 45.72 104.14) (xy 50.8 104.14)
		)
		(stroke
			(width 0)
			(type default)
		)
	)
	(wire
		(pts
			(xy 133.35 180.34) (xy 135.89 180.34)
		)
		(stroke
			(width 0)
			(type default)
		)
	)
	(wire
		(pts
			(xy 205.74 198.12) (xy 205.74 208.28)
		)
		(stroke
			(width 0)
			(type default)
		)
	)
	(wire
		(pts
			(xy 130.81 193.04) (xy 135.89 193.04)
		)
		(stroke
			(width 0)
			(type default)
		)
	)
	(wire
		(pts
			(xy 336.55 179.07) (xy 336.55 180.34)
		)
		(stroke
			(width 0)
			(type default)
		)
	)
	(wire
		(pts
			(xy 241.3 99.06) (xy 241.3 101.6)
		)
		(stroke
			(width 0)
			(type default)
		)
	)
	(wire
		(pts
			(xy 340.36 223.52) (xy 340.36 224.79)
		)
		(stroke
			(width 0)
			(type default)
		)
	)
	(wire
		(pts
			(xy 215.9 264.16) (xy 215.9 266.7)
		)
		(stroke
			(width 0)
			(type default)
		)
	)
	(wire
		(pts
			(xy 388.62 40.64) (xy 388.62 35.56)
		)
		(stroke
			(width 0)
			(type default)
		)
	)
	(wire
		(pts
			(xy 251.46 116.84) (xy 251.46 118.11)
		)
		(stroke
			(width 0)
			(type default)
		)
	)
	(wire
		(pts
			(xy 381 40.64) (xy 381 35.56)
		)
		(stroke
			(width 0)
			(type default)
		)
	)
	(wire
		(pts
			(xy 118.11 163.83) (xy 118.11 165.1)
		)
		(stroke
			(width 0)
			(type default)
		)
	)
	(label "VBUS"
		(at 58.42 33.02 0)
		(effects
			(font
				(size 1.27 1.27)
			)
			(justify left bottom)
		)
	)
	(label "USB_CC1"
		(at 74.93 82.55 90)
		(effects
			(font
				(size 1.27 1.27)
			)
			(justify left bottom)
		)
	)
	(label "FTDI_USER_PB"
		(at 290.83 132.08 180)
		(effects
			(font
				(size 1.27 1.27)
			)
			(justify right bottom)
		)
	)
	(label "SWDIO-JTMS"
		(at 151.13 251.46 0)
		(effects
			(font
				(size 1.27 1.27)
			)
			(justify left bottom)
		)
	)
	(label "FTDI_USER_PB"
		(at 134.62 203.2 180)
		(effects
			(font
				(size 1.27 1.27)
			)
			(justify right bottom)
		)
	)
	(label "USB_CC2"
		(at 57.15 40.64 180)
		(effects
			(font
				(size 1.27 1.27)
			)
			(justify right bottom)
		)
	)
	(label "SWCLK-JTCK"
		(at 151.13 256.54 0)
		(effects
			(font
				(size 1.27 1.27)
			)
			(justify left bottom)
		)
	)
	(label "USB_D_N"
		(at 60.96 190.5 0)
		(effects
			(font
				(size 1.27 1.27)
			)
			(justify left bottom)
		)
	)
	(label "JTDI"
		(at 151.13 265.43 0)
		(effects
			(font
				(size 1.27 1.27)
			)
			(justify left bottom)
		)
	)
	(label "USB_D_P"
		(at 127 50.8 180)
		(effects
			(font
				(size 1.27 1.27)
			)
			(justify right bottom)
		)
	)
	(label "OSC32_OUT"
		(at 287.02 137.16 180)
		(effects
			(font
				(size 1.27 1.27)
			)
			(justify right bottom)
		)
	)
	(label "USB_CC2"
		(at 78.74 82.55 90)
		(effects
			(font
				(size 1.27 1.27)
			)
			(justify left bottom)
		)
	)
	(label "NRST"
		(at 151.13 242.57 0)
		(effects
			(font
				(size 1.27 1.27)
			)
			(justify left bottom)
		)
	)
	(label "OSC32_IN"
		(at 195.58 198.12 0)
		(effects
			(font
				(size 1.27 1.27)
			)
			(justify left bottom)
		)
	)
	(label "USB_D_P"
		(at 60.96 187.96 0)
		(effects
			(font
				(size 1.27 1.27)
			)
			(justify left bottom)
		)
	)
	(label "LD2"
		(at 233.68 158.75 0)
		(effects
			(font
				(size 1.27 1.27)
			)
			(justify left bottom)
		)
	)
	(label "USB_D_N"
		(at 127 53.34 180)
		(effects
			(font
				(size 1.27 1.27)
			)
			(justify right bottom)
		)
	)
	(label "USB_CC1"
		(at 57.15 38.1 180)
		(effects
			(font
				(size 1.27 1.27)
			)
			(justify right bottom)
		)
	)
	(label "JTDO"
		(at 151.13 260.35 0)
		(effects
			(font
				(size 1.27 1.27)
			)
			(justify left bottom)
		)
	)
	(label "OSC32_OUT"
		(at 229.87 198.12 180)
		(effects
			(font
				(size 1.27 1.27)
			)
			(justify right bottom)
		)
	)
	(label "JTRST"
		(at 151.13 247.65 0)
		(effects
			(font
				(size 1.27 1.27)
			)
			(justify left bottom)
		)
	)
	(label "FRAM_WP"
		(at 281.94 71.12 0)
		(effects
			(font
				(size 1.27 1.27)
			)
			(justify left bottom)
		)
	)
	(label "FRAM_WP"
		(at 284.48 168.91 180)
		(effects
			(font
				(size 1.27 1.27)
			)
			(justify right bottom)
		)
	)
	(label "OSC32_IN"
		(at 285.75 134.62 180)
		(effects
			(font
				(size 1.27 1.27)
			)
			(justify right bottom)
		)
	)
	(global_label "I2C_1_SCL"
		(shape output)
		(at 229.87 168.91 180)
		(fields_autoplaced yes)
		(effects
			(font
				(size 1.27 1.27)
			)
			(justify right)
		)
		(property "Intersheetrefs" "${INTERSHEET_REFS}"
			(at 217.7202 168.8306 0)
			(effects
				(font
					(size 1.27 1.27)
				)
				(justify right)
				(hide yes)
			)
		)
	)
	(global_label "I2C_1_SCL"
		(shape input)
		(at 360.68 165.1 180)
		(fields_autoplaced yes)
		(effects
			(font
				(size 1.27 1.27)
			)
			(justify right)
		)
		(property "Intersheetrefs" "${INTERSHEET_REFS}"
			(at 348.5302 165.0206 0)
			(effects
				(font
					(size 1.27 1.27)
				)
				(justify right)
				(hide yes)
			)
		)
	)
	(global_label "SWCLK-JTCK"
		(shape bidirectional)
		(at 110.49 187.96 0)
		(fields_autoplaced yes)
		(effects
			(font
				(size 1.27 1.27)
			)
			(justify left)
		)
		(property "Intersheetrefs" "${INTERSHEET_REFS}"
			(at 125.1798 187.8806 0)
			(effects
				(font
					(size 1.27 1.27)
				)
				(justify left)
				(hide yes)
			)
		)
	)
	(global_label "I2C_1_SDA"
		(shape bidirectional)
		(at 360.68 167.64 180)
		(fields_autoplaced yes)
		(effects
			(font
				(size 1.27 1.27)
			)
			(justify right)
		)
		(property "Intersheetrefs" "${INTERSHEET_REFS}"
			(at 348.4698 167.5606 0)
			(effects
				(font
					(size 1.27 1.27)
				)
				(justify right)
				(hide yes)
			)
		)
	)
	(global_label "NRST"
		(shape output)
		(at 110.49 195.58 0)
		(fields_autoplaced yes)
		(effects
			(font
				(size 1.27 1.27)
			)
			(justify left)
		)
		(property "Intersheetrefs" "${INTERSHEET_REFS}"
			(at 117.6807 195.5006 0)
			(effects
				(font
					(size 1.27 1.27)
				)
				(justify left)
				(hide yes)
			)
		)
	)
	(global_label "NRST"
		(shape input)
		(at 195.58 146.05 180)
		(fields_autoplaced yes)
		(effects
			(font
				(size 1.27 1.27)
			)
			(justify right)
		)
		(property "Intersheetrefs" "${INTERSHEET_REFS}"
			(at 188.3893 145.9706 0)
			(effects
				(font
					(size 1.27 1.27)
				)
				(justify right)
				(hide yes)
			)
		)
	)
	(global_label "I2C_1_SCL"
		(shape input)
		(at 375.92 55.88 180)
		(fields_autoplaced yes)
		(effects
			(font
				(size 1.27 1.27)
			)
			(justify right)
		)
		(property "Intersheetrefs" "${INTERSHEET_REFS}"
			(at 363.7702 55.8006 0)
			(effects
				(font
					(size 1.27 1.27)
				)
				(justify right)
				(hide yes)
			)
		)
	)
	(global_label "I2C_1_SDA"
		(shape bidirectional)
		(at 261.62 50.8 180)
		(fields_autoplaced yes)
		(effects
			(font
				(size 1.27 1.27)
			)
			(justify right)
		)
		(property "Intersheetrefs" "${INTERSHEET_REFS}"
			(at 249.4098 50.7206 0)
			(effects
				(font
					(size 1.27 1.27)
				)
				(justify right)
				(hide yes)
			)
		)
	)
	(global_label "SWCLK-JTCK"
		(shape bidirectional)
		(at 229.87 181.61 180)
		(fields_autoplaced yes)
		(effects
			(font
				(size 1.27 1.27)
			)
			(justify right)
		)
		(property "Intersheetrefs" "${INTERSHEET_REFS}"
			(at 215.1802 181.5306 0)
			(effects
				(font
					(size 1.27 1.27)
				)
				(justify right)
				(hide yes)
			)
		)
	)
	(global_label "LPUART_1_STM_TX"
		(shape output)
		(at 229.87 151.13 180)
		(fields_autoplaced yes)
		(effects
			(font
				(size 1.27 1.27)
			)
			(justify right)
		)
		(property "Intersheetrefs" "${INTERSHEET_REFS}"
			(at 210.584 151.0506 0)
			(effects
				(font
					(size 1.27 1.27)
				)
				(justify right)
				(hide yes)
			)
		)
	)
	(global_label "I2C_1_SDA"
		(shape bidirectional)
		(at 340.36 220.98 180)
		(fields_autoplaced yes)
		(effects
			(font
				(size 1.27 1.27)
			)
			(justify right)
		)
		(property "Intersheetrefs" "${INTERSHEET_REFS}"
			(at 328.1498 220.9006 0)
			(effects
				(font
					(size 1.27 1.27)
				)
				(justify right)
				(hide yes)
			)
		)
	)
	(global_label "I2C_1_SDA"
		(shape bidirectional)
		(at 229.87 166.37 180)
		(fields_autoplaced yes)
		(effects
			(font
				(size 1.27 1.27)
			)
			(justify right)
		)
		(property "Intersheetrefs" "${INTERSHEET_REFS}"
			(at 217.6598 166.2906 0)
			(effects
				(font
					(size 1.27 1.27)
				)
				(justify right)
				(hide yes)
			)
		)
	)
	(global_label "I2C_1_SDA"
		(shape bidirectional)
		(at 375.92 50.8 180)
		(fields_autoplaced yes)
		(effects
			(font
				(size 1.27 1.27)
			)
			(justify right)
		)
		(property "Intersheetrefs" "${INTERSHEET_REFS}"
			(at 363.7098 50.7206 0)
			(effects
				(font
					(size 1.27 1.27)
				)
				(justify right)
				(hide yes)
			)
		)
	)
	(global_label "LPUART_1_STM_RX"
		(shape input)
		(at 229.87 153.67 180)
		(fields_autoplaced yes)
		(effects
			(font
				(size 1.27 1.27)
			)
			(justify right)
		)
		(property "Intersheetrefs" "${INTERSHEET_REFS}"
			(at 210.2817 153.5906 0)
			(effects
				(font
					(size 1.27 1.27)
				)
				(justify right)
				(hide yes)
			)
		)
	)
	(global_label "LPUART_1_STM_TX"
		(shape input)
		(at 142.24 190.5 0)
		(fields_autoplaced yes)
		(effects
			(font
				(size 1.27 1.27)
			)
			(justify left)
		)
		(property "Intersheetrefs" "${INTERSHEET_REFS}"
			(at 161.526 190.4206 0)
			(effects
				(font
					(size 1.27 1.27)
				)
				(justify left)
				(hide yes)
			)
		)
	)
	(global_label "I2C_1_SDA"
		(shape bidirectional)
		(at 294.64 163.83 0)
		(fields_autoplaced yes)
		(effects
			(font
				(size 1.27 1.27)
			)
			(justify left)
		)
		(property "Intersheetrefs" "${INTERSHEET_REFS}"
			(at 306.8502 163.7506 0)
			(effects
				(font
					(size 1.27 1.27)
				)
				(justify left)
				(hide yes)
			)
		)
	)
	(global_label "JTDO"
		(shape bidirectional)
		(at 288.29 148.59 0)
		(fields_autoplaced yes)
		(effects
			(font
				(size 1.27 1.27)
			)
			(justify left)
		)
		(property "Intersheetrefs" "${INTERSHEET_REFS}"
			(at 295.2388 148.5106 0)
			(effects
				(font
					(size 1.27 1.27)
				)
				(justify left)
				(hide yes)
			)
		)
	)
	(global_label "I2C_1_SCL"
		(shape input)
		(at 203.2 251.46 180)
		(fields_autoplaced yes)
		(effects
			(font
				(size 1.27 1.27)
			)
			(justify right)
		)
		(property "Intersheetrefs" "${INTERSHEET_REFS}"
			(at 191.0502 251.3806 0)
			(effects
				(font
					(size 1.27 1.27)
				)
				(justify right)
				(hide yes)
			)
		)
	)
	(global_label "LPUART_1_STM_RX"
		(shape output)
		(at 143.51 180.34 0)
		(fields_autoplaced yes)
		(effects
			(font
				(size 1.27 1.27)
			)
			(justify left)
		)
		(property "Intersheetrefs" "${INTERSHEET_REFS}"
			(at 163.0983 180.2606 0)
			(effects
				(font
					(size 1.27 1.27)
				)
				(justify left)
				(hide yes)
			)
		)
	)
	(global_label "SWDIO-JTMS"
		(shape bidirectional)
		(at 110.49 185.42 0)
		(fields_autoplaced yes)
		(effects
			(font
				(size 1.27 1.27)
			)
			(justify left)
		)
		(property "Intersheetrefs" "${INTERSHEET_REFS}"
			(at 124.9379 185.3406 0)
			(effects
				(font
					(size 1.27 1.27)
				)
				(justify left)
				(hide yes)
			)
		)
	)
	(global_label "SWDIO-JTMS"
		(shape bidirectional)
		(at 229.87 179.07 180)
		(fields_autoplaced yes)
		(effects
			(font
				(size 1.27 1.27)
			)
			(justify right)
		)
		(property "Intersheetrefs" "${INTERSHEET_REFS}"
			(at 215.4221 178.9906 0)
			(effects
				(font
					(size 1.27 1.27)
				)
				(justify right)
				(hide yes)
			)
		)
	)
	(global_label "I2C_1_SDA"
		(shape bidirectional)
		(at 351.79 124.46 180)
		(fields_autoplaced yes)
		(effects
			(font
				(size 1.27 1.27)
			)
			(justify right)
		)
		(property "Intersheetrefs" "${INTERSHEET_REFS}"
			(at 339.5798 124.3806 0)
			(effects
				(font
					(size 1.27 1.27)
				)
				(justify right)
				(hide yes)
			)
		)
	)
	(global_label "JTRST"
		(shape bidirectional)
		(at 110.49 193.04 0)
		(fields_autoplaced yes)
		(effects
			(font
				(size 1.27 1.27)
			)
			(justify left)
		)
		(property "Intersheetrefs" "${INTERSHEET_REFS}"
			(at 118.2855 192.9606 0)
			(effects
				(font
					(size 1.27 1.27)
				)
				(justify left)
				(hide yes)
			)
		)
	)
	(global_label "I2C_1_SCL"
		(shape input)
		(at 351.79 129.54 180)
		(fields_autoplaced yes)
		(effects
			(font
				(size 1.27 1.27)
			)
			(justify right)
		)
		(property "Intersheetrefs" "${INTERSHEET_REFS}"
			(at 339.6402 129.4606 0)
			(effects
				(font
					(size 1.27 1.27)
				)
				(justify right)
				(hide yes)
			)
		)
	)
	(global_label "LPUART_1_STM_RX"
		(shape output)
		(at 142.24 193.04 0)
		(fields_autoplaced yes)
		(effects
			(font
				(size 1.27 1.27)
			)
			(justify left)
		)
		(property "Intersheetrefs" "${INTERSHEET_REFS}"
			(at 161.8283 192.9606 0)
			(effects
				(font
					(size 1.27 1.27)
				)
				(justify left)
				(hide yes)
			)
		)
	)
	(global_label "I2C_1_SCL"
		(shape input)
		(at 261.62 55.88 180)
		(fields_autoplaced yes)
		(effects
			(font
				(size 1.27 1.27)
			)
			(justify right)
		)
		(property "Intersheetrefs" "${INTERSHEET_REFS}"
			(at 249.4702 55.8006 0)
			(effects
				(font
					(size 1.27 1.27)
				)
				(justify right)
				(hide yes)
			)
		)
	)
	(global_label "I2C_1_SCL"
		(shape input)
		(at 340.36 218.44 180)
		(fields_autoplaced yes)
		(effects
			(font
				(size 1.27 1.27)
			)
			(justify right)
		)
		(property "Intersheetrefs" "${INTERSHEET_REFS}"
			(at 328.2102 218.3606 0)
			(effects
				(font
					(size 1.27 1.27)
				)
				(justify right)
				(hide yes)
			)
		)
	)
	(global_label "I2C_1_SCL"
		(shape output)
		(at 294.64 161.29 0)
		(fields_autoplaced yes)
		(effects
			(font
				(size 1.27 1.27)
			)
			(justify left)
		)
		(property "Intersheetrefs" "${INTERSHEET_REFS}"
			(at 306.7898 161.2106 0)
			(effects
				(font
					(size 1.27 1.27)
				)
				(justify left)
				(hide yes)
			)
		)
	)
	(global_label "JTDI"
		(shape bidirectional)
		(at 229.87 184.15 180)
		(fields_autoplaced yes)
		(effects
			(font
				(size 1.27 1.27)
			)
			(justify right)
		)
		(property "Intersheetrefs" "${INTERSHEET_REFS}"
			(at 223.6469 184.0706 0)
			(effects
				(font
					(size 1.27 1.27)
				)
				(justify right)
				(hide yes)
			)
		)
	)
	(global_label "JTDO"
		(shape bidirectional)
		(at 110.49 198.12 0)
		(fields_autoplaced yes)
		(effects
			(font
				(size 1.27 1.27)
			)
			(justify left)
		)
		(property "Intersheetrefs" "${INTERSHEET_REFS}"
			(at 117.4388 198.0406 0)
			(effects
				(font
					(size 1.27 1.27)
				)
				(justify left)
				(hide yes)
			)
		)
	)
	(global_label "I2C_1_SCL"
		(shape output)
		(at 228.6 186.69 180)
		(fields_autoplaced yes)
		(effects
			(font
				(size 1.27 1.27)
			)
			(justify right)
		)
		(property "Intersheetrefs" "${INTERSHEET_REFS}"
			(at 216.4502 186.6106 0)
			(effects
				(font
					(size 1.27 1.27)
				)
				(justify right)
				(hide yes)
			)
		)
	)
	(global_label "JTDI"
		(shape bidirectional)
		(at 110.49 200.66 0)
		(fields_autoplaced yes)
		(effects
			(font
				(size 1.27 1.27)
			)
			(justify left)
		)
		(property "Intersheetrefs" "${INTERSHEET_REFS}"
			(at 116.7131 200.5806 0)
			(effects
				(font
					(size 1.27 1.27)
				)
				(justify left)
				(hide yes)
			)
		)
	)
	(global_label "LPUART_1_STM_TX"
		(shape input)
		(at 143.51 182.88 0)
		(fields_autoplaced yes)
		(effects
			(font
				(size 1.27 1.27)
			)
			(justify left)
		)
		(property "Intersheetrefs" "${INTERSHEET_REFS}"
			(at 162.796 182.8006 0)
			(effects
				(font
					(size 1.27 1.27)
				)
				(justify left)
				(hide yes)
			)
		)
	)
	(global_label "JTRST"
		(shape bidirectional)
		(at 288.29 151.13 0)
		(fields_autoplaced yes)
		(effects
			(font
				(size 1.27 1.27)
			)
			(justify left)
		)
		(property "Intersheetrefs" "${INTERSHEET_REFS}"
			(at 296.0855 151.0506 0)
			(effects
				(font
					(size 1.27 1.27)
				)
				(justify left)
				(hide yes)
			)
		)
	)
	(global_label "I2C_1_SDA"
		(shape bidirectional)
		(at 203.2 254 180)
		(fields_autoplaced yes)
		(effects
			(font
				(size 1.27 1.27)
			)
			(justify right)
		)
		(property "Intersheetrefs" "${INTERSHEET_REFS}"
			(at 190.9898 253.9206 0)
			(effects
				(font
					(size 1.27 1.27)
				)
				(justify right)
				(hide yes)
			)
		)
	)
	(symbol
		(lib_id "antmicropower:GND")
		(at 287.02 217.17 0)
		(mirror y)
		(unit 1)
		(exclude_from_sim no)
		(in_bom yes)
		(on_board yes)
		(dnp no)
		(fields_autoplaced yes)
		(property "Reference" "#PWR048"
			(at 287.02 223.52 0)
			(effects
				(font
					(size 1.27 1.27)
				)
				(hide yes)
			)
		)
		(property "Value" "GND"
			(at 287.02 222.25 0)
			(effects
				(font
					(size 1.27 1.27)
				)
			)
		)
		(property "Footprint" ""
			(at 287.02 217.17 0)
			(effects
				(font
					(size 1.27 1.27)
				)
				(hide yes)
			)
		)
		(property "Datasheet" ""
			(at 287.02 217.17 0)
			(effects
				(font
					(size 1.27 1.27)
				)
				(hide yes)
			)
		)
		(property "Description" ""
			(at 287.02 217.17 0)
			(effects
				(font
					(size 1.27 1.27)
				)
				(hide yes)
			)
		)
		(property "Author" "Antmicro"
			(at 278.13 224.79 0)
			(effects
				(font
					(size 1.27 1.27)
					(thickness 0.15)
				)
				(justify left bottom)
				(hide yes)
			)
		)
		(property "License" "Apache-2.0"
			(at 278.13 227.33 0)
			(effects
				(font
					(size 1.27 1.27)
					(thickness 0.15)
				)
				(justify left bottom)
				(hide yes)
			)
		)
		(pin "1"
		)
		(instances
			(project "environment-sensor"
				(path ""
					(reference "#PWR048")
					(unit 1)
				)
			)
		)
	)
	(symbol
		(lib_id "antmicroCapacitors0402:C_100n_0402")
		(at 264.16 116.84 90)
		(unit 1)
		(exclude_from_sim no)
		(in_bom yes)
		(on_board yes)
		(dnp no)
		(fields_autoplaced yes)
		(property "Reference" "C15"
			(at 261.62 113.0235 90)
			(effects
				(font
					(size 1.27 1.27)
					(thickness 0.15)
				)
				(justify left)
			)
		)
		(property "Value" "C_100n_0402"
			(at 274.32 96.52 0)
			(effects
				(font
					(size 1.27 1.27)
					(thickness 0.15)
				)
				(justify left bottom)
				(hide yes)
			)
		)
		(property "Footprint" "antmicro-footprints:C_0402_1005Metric"
			(at 276.86 96.52 0)
			(effects
				(font
					(size 1.27 1.27)
					(thickness 0.15)
				)
				(justify left bottom)
				(hide yes)
			)
		)
		(property "Datasheet" "https://www.murata.com/products/productdetail?partno=GRM155R61H104KE14%23"
			(at 279.4 96.52 0)
			(effects
				(font
					(size 1.27 1.27)
					(thickness 0.15)
				)
				(justify left bottom)
				(hide yes)
			)
		)
		(property "Description" "SMD Multilayer Ceramic Capacitor, 0.1 µF, 50 V, 0402 [1005 Metric], ± 10%, X5R, GRM Series"
			(at 264.16 116.84 0)
			(effects
				(font
					(size 1.27 1.27)
				)
				(hide yes)
			)
		)
		(property "Manufacturer" "Murata"
			(at 284.48 96.52 0)
			(effects
				(font
					(size 1.27 1.27)
					(thickness 0.15)
				)
				(justify left bottom)
				(hide yes)
			)
		)
		(property "MPN" "GRM155R61H104KE14D"
			(at 281.94 96.52 0)
			(effects
				(font
					(size 1.27 1.27)
					(thickness 0.15)
				)
				(justify left bottom)
				(hide yes)
			)
		)
		(property "Val" "100n"
			(at 261.62 115.5635 90)
			(effects
				(font
					(size 1.27 1.27)
					(thickness 0.15)
				)
				(justify left)
			)
		)
		(property "License" "Apache-2.0"
			(at 287.02 96.52 0)
			(effects
				(font
					(size 1.27 1.27)
					(thickness 0.15)
				)
				(justify left bottom)
				(hide yes)
			)
		)
		(property "Author" "Antmicro"
			(at 289.56 96.52 0)
			(effects
				(font
					(size 1.27 1.27)
					(thickness 0.15)
				)
				(justify left bottom)
				(hide yes)
			)
		)
		(property "Voltage" "50V"
			(at 292.1 96.52 0)
			(effects
				(font
					(size 1.27 1.27)
				)
				(justify left bottom)
				(hide yes)
			)
		)
		(property "Dielectric" "X5R"
			(at 294.64 96.52 0)
			(effects
				(font
					(size 1.27 1.27)
				)
				(justify left bottom)
				(hide yes)
			)
		)
		(property "Public" "False"
			(at 297.18 96.52 0)
			(effects
				(font
					(size 1.27 1.27)
				)
				(justify left bottom)
				(hide yes)
			)
		)
		(pin "1"
		)
		(pin "2"
		)
		(instances
			(project "environment-sensor"
				(path ""
					(reference "C15")
					(unit 1)
				)
			)
		)
	)
	(symbol
		(lib_id "antmicropower:+5V")
		(at 149.86 41.91 0)
		(unit 1)
		(exclude_from_sim no)
		(in_bom yes)
		(on_board yes)
		(dnp no)
		(fields_autoplaced yes)
		(property "Reference" "#PWR019"
			(at 165.1 44.45 0)
			(effects
				(font
					(size 1.27 1.27)
					(thickness 0.15)
				)
				(justify left bottom)
				(hide yes)
			)
		)
		(property "Value" "+5V"
			(at 149.86 36.83 0)
			(effects
				(font
					(size 1.27 1.27)
					(thickness 0.15)
				)
			)
		)
		(property "Footprint" ""
			(at 165.1 49.53 0)
			(effects
				(font
					(size 1.27 1.27)
					(thickness 0.15)
				)
				(justify left bottom)
				(hide yes)
			)
		)
		(property "Datasheet" ""
			(at 165.1 52.07 0)
			(effects
				(font
					(size 1.27 1.27)
					(thickness 0.15)
				)
				(justify left bottom)
				(hide yes)
			)
		)
		(property "Description" ""
			(at 149.86 41.91 0)
			(effects
				(font
					(size 1.27 1.27)
				)
				(hide yes)
			)
		)
		(property "Author" "Antmicro"
			(at 165.1 49.53 0)
			(effects
				(font
					(size 1.27 1.27)
					(thickness 0.15)
				)
				(justify left bottom)
				(hide yes)
			)
		)
		(property "License" "Apache-2.0"
			(at 165.1 52.07 0)
			(effects
				(font
					(size 1.27 1.27)
					(thickness 0.15)
				)
				(justify left bottom)
				(hide yes)
			)
		)
		(pin "1"
		)
		(instances
			(project "environment-sensor"
				(path ""
					(reference "#PWR019")
					(unit 1)
				)
			)
		)
	)
	(symbol
		(lib_id "antmicroCapacitors0402:C_2u2_0402")
		(at 149.86 60.96 270)
		(unit 1)
		(exclude_from_sim no)
		(in_bom yes)
		(on_board yes)
		(dnp no)
		(fields_autoplaced yes)
		(property "Reference" "C7"
			(at 152.4 62.2362 90)
			(effects
				(font
					(size 1.27 1.27)
					(thickness 0.15)
				)
				(justify left)
			)
		)
		(property "Value" "C_2u2_0402"
			(at 139.7 81.28 0)
			(effects
				(font
					(size 1.27 1.27)
					(thickness 0.15)
				)
				(justify left bottom)
				(hide yes)
			)
		)
		(property "Footprint" "antmicro-footprints:C_0402_1005Metric"
			(at 137.16 81.28 0)
			(effects
				(font
					(size 1.27 1.27)
					(thickness 0.15)
				)
				(justify left bottom)
				(hide yes)
			)
		)
		(property "Datasheet" "https://product.tdk.com/en/search/capacitor/ceramic/mlcc/info?part_no=C1005X5R1A225K050BC"
			(at 134.62 81.28 0)
			(effects
				(font
					(size 1.27 1.27)
					(thickness 0.15)
				)
				(justify left bottom)
				(hide yes)
			)
		)
		(property "Description" "SMD Multilayer Ceramic Capacitor, 2.2 µF, 10 V, 0402 [1005 Metric], ± 10%, X5R, C"
			(at 149.86 60.96 0)
			(effects
				(font
					(size 1.27 1.27)
				)
				(hide yes)
			)
		)
		(property "Manufacturer" "TDK"
			(at 129.54 81.28 0)
			(effects
				(font
					(size 1.27 1.27)
					(thickness 0.15)
				)
				(justify left bottom)
				(hide yes)
			)
		)
		(property "MPN" "C1005X5R1A225K050BC"
			(at 132.08 81.28 0)
			(effects
				(font
					(size 1.27 1.27)
					(thickness 0.15)
				)
				(justify left bottom)
				(hide yes)
			)
		)
		(property "Val" "2u2"
			(at 152.4 64.7762 90)
			(effects
				(font
					(size 1.27 1.27)
					(thickness 0.15)
				)
				(justify left)
			)
		)
		(property "License" "Apache-2.0"
			(at 127 81.28 0)
			(effects
				(font
					(size 1.27 1.27)
					(thickness 0.15)
				)
				(justify left bottom)
				(hide yes)
			)
		)
		(property "Author" "Antmicro"
			(at 124.46 81.28 0)
			(effects
				(font
					(size 1.27 1.27)
					(thickness 0.15)
				)
				(justify left bottom)
				(hide yes)
			)
		)
		(property "Voltage" ""
			(at 121.92 81.28 0)
			(effects
				(font
					(size 1.27 1.27)
				)
				(justify left bottom)
				(hide yes)
			)
		)
		(property "Dielectric" ""
			(at 119.38 81.28 0)
			(effects
				(font
					(size 1.27 1.27)
				)
				(justify left bottom)
				(hide yes)
			)
		)
		(property "Public" "False"
			(at 116.84 81.28 0)
			(effects
				(font
					(size 1.27 1.27)
				)
				(justify left bottom)
				(hide yes)
			)
		)
		(pin "1"
		)
		(pin "2"
		)
		(instances
			(project "environment-sensor"
				(path ""
					(reference "C7")
					(unit 1)
				)
			)
		)
	)
	(symbol
		(lib_id "antmicroCapacitors0402:C_100n_0402")
		(at 398.78 154.94 270)
		(unit 1)
		(exclude_from_sim no)
		(in_bom yes)
		(on_board yes)
		(dnp no)
		(fields_autoplaced yes)
		(property "Reference" "C28"
			(at 401.32 156.2162 90)
			(effects
				(font
					(size 1.27 1.27)
					(thickness 0.15)
				)
				(justify left)
			)
		)
		(property "Value" "C_100n_0402"
			(at 388.62 175.26 0)
			(effects
				(font
					(size 1.27 1.27)
					(thickness 0.15)
				)
				(justify left bottom)
				(hide yes)
			)
		)
		(property "Footprint" "antmicro-footprints:C_0402_1005Metric"
			(at 386.08 175.26 0)
			(effects
				(font
					(size 1.27 1.27)
					(thickness 0.15)
				)
				(justify left bottom)
				(hide yes)
			)
		)
		(property "Datasheet" "https://www.murata.com/products/productdetail?partno=GRM155R61H104KE14%23"
			(at 383.54 175.26 0)
			(effects
				(font
					(size 1.27 1.27)
					(thickness 0.15)
				)
				(justify left bottom)
				(hide yes)
			)
		)
		(property "Description" "SMD Multilayer Ceramic Capacitor, 0.1 µF, 50 V, 0402 [1005 Metric], ± 10%, X5R, GRM Series"
			(at 398.78 154.94 0)
			(effects
				(font
					(size 1.27 1.27)
				)
				(hide yes)
			)
		)
		(property "Manufacturer" "Murata"
			(at 378.46 175.26 0)
			(effects
				(font
					(size 1.27 1.27)
					(thickness 0.15)
				)
				(justify left bottom)
				(hide yes)
			)
		)
		(property "MPN" "GRM155R61H104KE14D"
			(at 381 175.26 0)
			(effects
				(font
					(size 1.27 1.27)
					(thickness 0.15)
				)
				(justify left bottom)
				(hide yes)
			)
		)
		(property "Val" "100n"
			(at 401.32 158.7562 90)
			(effects
				(font
					(size 1.27 1.27)
					(thickness 0.15)
				)
				(justify left)
			)
		)
		(property "License" "Apache-2.0"
			(at 375.92 175.26 0)
			(effects
				(font
					(size 1.27 1.27)
					(thickness 0.15)
				)
				(justify left bottom)
				(hide yes)
			)
		)
		(property "Author" "Antmicro"
			(at 373.38 175.26 0)
			(effects
				(font
					(size 1.27 1.27)
					(thickness 0.15)
				)
				(justify left bottom)
				(hide yes)
			)
		)
		(property "Voltage" "50V"
			(at 370.84 175.26 0)
			(effects
				(font
					(size 1.27 1.27)
				)
				(justify left bottom)
				(hide yes)
			)
		)
		(property "Dielectric" "X5R"
			(at 368.3 175.26 0)
			(effects
				(font
					(size 1.27 1.27)
				)
				(justify left bottom)
				(hide yes)
			)
		)
		(property "Public" "False"
			(at 365.76 175.26 0)
			(effects
				(font
					(size 1.27 1.27)
				)
				(justify left bottom)
				(hide yes)
			)
		)
		(pin "1"
		)
		(pin "2"
		)
		(instances
			(project "environment-sensor"
				(path ""
					(reference "C28")
					(unit 1)
				)
			)
		)
	)
	(symbol
		(lib_id "antmicroCapacitors0402:C_100n_0402")
		(at 107.95 170.18 90)
		(unit 1)
		(exclude_from_sim no)
		(in_bom yes)
		(on_board yes)
		(dnp no)
		(fields_autoplaced yes)
		(property "Reference" "C5"
			(at 110.49 166.3635 90)
			(effects
				(font
					(size 1.27 1.27)
					(thickness 0.15)
				)
				(justify right)
			)
		)
		(property "Value" "C_100n_0402"
			(at 118.11 149.86 0)
			(effects
				(font
					(size 1.27 1.27)
					(thickness 0.15)
				)
				(justify left bottom)
				(hide yes)
			)
		)
		(property "Footprint" "antmicro-footprints:C_0402_1005Metric"
			(at 120.65 149.86 0)
			(effects
				(font
					(size 1.27 1.27)
					(thickness 0.15)
				)
				(justify left bottom)
				(hide yes)
			)
		)
		(property "Datasheet" "https://www.murata.com/products/productdetail?partno=GRM155R61H104KE14%23"
			(at 123.19 149.86 0)
			(effects
				(font
					(size 1.27 1.27)
					(thickness 0.15)
				)
				(justify left bottom)
				(hide yes)
			)
		)
		(property "Description" "SMD Multilayer Ceramic Capacitor, 0.1 µF, 50 V, 0402 [1005 Metric], ± 10%, X5R, GRM Series"
			(at 107.95 170.18 0)
			(effects
				(font
					(size 1.27 1.27)
				)
				(hide yes)
			)
		)
		(property "Manufacturer" "Murata"
			(at 128.27 149.86 0)
			(effects
				(font
					(size 1.27 1.27)
					(thickness 0.15)
				)
				(justify left bottom)
				(hide yes)
			)
		)
		(property "MPN" "GRM155R61H104KE14D"
			(at 125.73 149.86 0)
			(effects
				(font
					(size 1.27 1.27)
					(thickness 0.15)
				)
				(justify left bottom)
				(hide yes)
			)
		)
		(property "Val" "100n"
			(at 110.49 168.9035 90)
			(effects
				(font
					(size 1.27 1.27)
					(thickness 0.15)
				)
				(justify right)
			)
		)
		(property "License" "Apache-2.0"
			(at 130.81 149.86 0)
			(effects
				(font
					(size 1.27 1.27)
					(thickness 0.15)
				)
				(justify left bottom)
				(hide yes)
			)
		)
		(property "Author" "Antmicro"
			(at 133.35 149.86 0)
			(effects
				(font
					(size 1.27 1.27)
					(thickness 0.15)
				)
				(justify left bottom)
				(hide yes)
			)
		)
		(property "Voltage" "50V"
			(at 135.89 149.86 0)
			(effects
				(font
					(size 1.27 1.27)
				)
				(justify left bottom)
				(hide yes)
			)
		)
		(property "Dielectric" "X5R"
			(at 138.43 149.86 0)
			(effects
				(font
					(size 1.27 1.27)
				)
				(justify left bottom)
				(hide yes)
			)
		)
		(property "Public" "False"
			(at 140.97 149.86 0)
			(effects
				(font
					(size 1.27 1.27)
				)
				(justify left bottom)
				(hide yes)
			)
		)
		(pin "1"
		)
		(pin "2"
		)
		(instances
			(project "environment-sensor"
				(path ""
					(reference "C5")
					(unit 1)
				)
			)
		)
	)
	(symbol
		(lib_id "antmicropower:GND")
		(at 336.55 180.34 0)
		(mirror y)
		(unit 1)
		(exclude_from_sim no)
		(in_bom yes)
		(on_board yes)
		(dnp no)
		(fields_autoplaced yes)
		(property "Reference" "#PWR062"
			(at 336.55 186.69 0)
			(effects
				(font
					(size 1.27 1.27)
				)
				(hide yes)
			)
		)
		(property "Value" "GND"
			(at 336.55 185.42 0)
			(effects
				(font
					(size 1.27 1.27)
				)
			)
		)
		(property "Footprint" ""
			(at 336.55 180.34 0)
			(effects
				(font
					(size 1.27 1.27)
				)
				(hide yes)
			)
		)
		(property "Datasheet" ""
			(at 336.55 180.34 0)
			(effects
				(font
					(size 1.27 1.27)
				)
				(hide yes)
			)
		)
		(property "Description" ""
			(at 336.55 180.34 0)
			(effects
				(font
					(size 1.27 1.27)
				)
				(hide yes)
			)
		)
		(property "Author" "Antmicro"
			(at 327.66 187.96 0)
			(effects
				(font
					(size 1.27 1.27)
					(thickness 0.15)
				)
				(justify left bottom)
				(hide yes)
			)
		)
		(property "License" "Apache-2.0"
			(at 327.66 190.5 0)
			(effects
				(font
					(size 1.27 1.27)
					(thickness 0.15)
				)
				(justify left bottom)
				(hide yes)
			)
		)
		(pin "1"
		)
		(instances
			(project "environment-sensor"
				(path ""
					(reference "#PWR062")
					(unit 1)
				)
			)
		)
	)
	(symbol
		(lib_id "antmicropower:+3V3")
		(at 293.37 58.42 0)
		(mirror y)
		(unit 1)
		(exclude_from_sim no)
		(in_bom yes)
		(on_board yes)
		(dnp no)
		(fields_autoplaced yes)
		(property "Reference" "#PWR049"
			(at 293.37 62.23 0)
			(effects
				(font
					(size 1.27 1.27)
				)
				(hide yes)
			)
		)
		(property "Value" "+3V3"
			(at 293.37 52.07 0)
			(effects
				(font
					(size 1.27 1.27)
				)
			)
		)
		(property "Footprint" ""
			(at 293.37 58.42 0)
			(effects
				(font
					(size 1.27 1.27)
				)
				(hide yes)
			)
		)
		(property "Datasheet" ""
			(at 293.37 58.42 0)
			(effects
				(font
					(size 1.27 1.27)
				)
				(hide yes)
			)
		)
		(property "Description" ""
			(at 293.37 58.42 0)
			(effects
				(font
					(size 1.27 1.27)
				)
				(hide yes)
			)
		)
		(property "Author" "Antmicro"
			(at 278.13 60.96 0)
			(effects
				(font
					(size 1.27 1.27)
					(thickness 0.15)
				)
				(justify left bottom)
				(hide yes)
			)
		)
		(property "License" "Apache-2.0"
			(at 278.13 63.5 0)
			(effects
				(font
					(size 1.27 1.27)
					(thickness 0.15)
				)
				(justify left bottom)
				(hide yes)
			)
		)
		(pin "1"
		)
		(instances
			(project "environment-sensor"
				(path ""
					(reference "#PWR049")
					(unit 1)
				)
			)
		)
	)
	(symbol
		(lib_id "antmicropower:+3V3")
		(at 289.56 138.43 0)
		(unit 1)
		(exclude_from_sim no)
		(in_bom yes)
		(on_board yes)
		(dnp no)
		(fields_autoplaced yes)
		(property "Reference" "#PWR047"
			(at 289.56 142.24 0)
			(effects
				(font
					(size 1.27 1.27)
				)
				(hide yes)
			)
		)
		(property "Value" "+3V3"
			(at 289.56 133.35 0)
			(effects
				(font
					(size 1.27 1.27)
				)
			)
		)
		(property "Footprint" ""
			(at 289.56 138.43 0)
			(effects
				(font
					(size 1.27 1.27)
				)
				(hide yes)
			)
		)
		(property "Datasheet" ""
			(at 289.56 138.43 0)
			(effects
				(font
					(size 1.27 1.27)
				)
				(hide yes)
			)
		)
		(property "Description" ""
			(at 289.56 138.43 0)
			(effects
				(font
					(size 1.27 1.27)
				)
				(hide yes)
			)
		)
		(property "Author" "Antmicro"
			(at 304.8 140.97 0)
			(effects
				(font
					(size 1.27 1.27)
					(thickness 0.15)
				)
				(justify left bottom)
				(hide yes)
			)
		)
		(property "License" "Apache-2.0"
			(at 304.8 143.51 0)
			(effects
				(font
					(size 1.27 1.27)
					(thickness 0.15)
				)
				(justify left bottom)
				(hide yes)
			)
		)
		(pin "1"
		)
		(instances
			(project "environment-sensor"
				(path ""
					(reference "#PWR047")
					(unit 1)
				)
			)
		)
	)
	(symbol
		(lib_id "antmicropower:GND")
		(at 74.93 115.57 0)
		(unit 1)
		(exclude_from_sim no)
		(in_bom yes)
		(on_board yes)
		(dnp no)
		(fields_autoplaced yes)
		(property "Reference" "#PWR010"
			(at 74.93 121.92 0)
			(effects
				(font
					(size 1.27 1.27)
				)
				(hide yes)
			)
		)
		(property "Value" "GND"
			(at 72.39 116.8399 0)
			(effects
				(font
					(size 1.27 1.27)
				)
				(justify right)
			)
		)
		(property "Footprint" ""
			(at 74.93 115.57 0)
			(effects
				(font
					(size 1.27 1.27)
				)
				(hide yes)
			)
		)
		(property "Datasheet" ""
			(at 74.93 115.57 0)
			(effects
				(font
					(size 1.27 1.27)
				)
				(hide yes)
			)
		)
		(property "Description" ""
			(at 74.93 115.57 0)
			(effects
				(font
					(size 1.27 1.27)
				)
				(hide yes)
			)
		)
		(property "Author" "Antmicro"
			(at 83.82 123.19 0)
			(effects
				(font
					(size 1.27 1.27)
					(thickness 0.15)
				)
				(justify left bottom)
				(hide yes)
			)
		)
		(property "License" "Apache-2.0"
			(at 83.82 125.73 0)
			(effects
				(font
					(size 1.27 1.27)
					(thickness 0.15)
				)
				(justify left bottom)
				(hide yes)
			)
		)
		(pin "1"
		)
		(instances
			(project "environment-sensor"
				(path ""
					(reference "#PWR010")
					(unit 1)
				)
			)
		)
	)
	(symbol
		(lib_id "antmicroResistors0402:R_0R_0402")
		(at 135.89 190.5 0)
		(mirror x)
		(unit 1)
		(exclude_from_sim no)
		(in_bom no)
		(on_board yes)
		(dnp yes)
		(fields_autoplaced yes)
		(property "Reference" "R15"
			(at 135.89 187.96 0)
			(effects
				(font
					(size 1.27 1.27)
					(thickness 0.15)
				)
			)
		)
		(property "Value" "R_0R_0402"
			(at 156.21 177.8 0)
			(effects
				(font
					(size 1.27 1.27)
					(thickness 0.15)
				)
				(justify left bottom)
				(hide yes)
			)
		)
		(property "Footprint" "antmicro-footprints:R_0402_1005Metric"
			(at 156.21 175.26 0)
			(effects
				(font
					(size 1.27 1.27)
					(thickness 0.15)
				)
				(justify left bottom)
				(hide yes)
			)
		)
		(property "Datasheet" "https://industrial.panasonic.com/cdbs/www-data/pdf/RDA0000/AOA0000C301.pdf"
			(at 156.21 172.72 0)
			(effects
				(font
					(size 1.27 1.27)
					(thickness 0.15)
				)
				(justify left bottom)
				(hide yes)
			)
		)
		(property "Description" "SMD Chip Resistor, Jumper, 0 ohm, 100 mW, 0402 [1005 Metric], Thick Film, General Purpose"
			(at 135.89 190.5 0)
			(effects
				(font
					(size 1.27 1.27)
				)
				(hide yes)
			)
		)
		(property "Manufacturer" "Panasonic"
			(at 156.21 167.64 0)
			(effects
				(font
					(size 1.27 1.27)
					(thickness 0.15)
				)
				(justify left bottom)
				(hide yes)
			)
		)
		(property "MPN" "ERJ2GE0R00X"
			(at 156.21 170.18 0)
			(effects
				(font
					(size 1.27 1.27)
					(thickness 0.15)
				)
				(justify left bottom)
				(hide yes)
			)
		)
		(property "Val" "0R"
			(at 139.7 187.96 0)
			(effects
				(font
					(size 1.27 1.27)
					(thickness 0.15)
				)
			)
		)
		(property "License" "Apache-2.0"
			(at 156.21 165.1 0)
			(effects
				(font
					(size 1.27 1.27)
					(thickness 0.15)
				)
				(justify left bottom)
				(hide yes)
			)
		)
		(property "Author" "Antmicro"
			(at 156.21 162.56 0)
			(effects
				(font
					(size 1.27 1.27)
					(thickness 0.15)
				)
				(justify left bottom)
				(hide yes)
			)
		)
		(property "Tolerance" "~"
			(at 156.21 180.34 0)
			(effects
				(font
					(size 1.27 1.27)
				)
				(justify left bottom)
				(hide yes)
			)
		)
		(property "Current" "1A"
			(at 138.43 190.5 0)
			(effects
				(font
					(size 1.27 1.27)
					(thickness 0.15)
				)
				(hide yes)
			)
		)
		(property "Public" "False"
			(at 156.21 160.02 0)
			(effects
				(font
					(size 1.27 1.27)
				)
				(justify left bottom)
				(hide yes)
			)
		)
		(pin "1"
		)
		(pin "2"
		)
		(instances
			(project "environment-sensor"
				(path ""
					(reference "R15")
					(unit 1)
				)
			)
		)
	)
	(symbol
		(lib_id "antmicropower:GND")
		(at 99.06 73.66 0)
		(unit 1)
		(exclude_from_sim no)
		(in_bom yes)
		(on_board yes)
		(dnp no)
		(fields_autoplaced yes)
		(property "Reference" "#PWR014"
			(at 99.06 80.01 0)
			(effects
				(font
					(size 1.27 1.27)
				)
				(hide yes)
			)
		)
		(property "Value" "GND"
			(at 99.06 78.74 0)
			(effects
				(font
					(size 1.27 1.27)
				)
			)
		)
		(property "Footprint" ""
			(at 99.06 73.66 0)
			(effects
				(font
					(size 1.27 1.27)
				)
				(hide yes)
			)
		)
		(property "Datasheet" ""
			(at 99.06 73.66 0)
			(effects
				(font
					(size 1.27 1.27)
				)
				(hide yes)
			)
		)
		(property "Description" ""
			(at 99.06 73.66 0)
			(effects
				(font
					(size 1.27 1.27)
				)
				(hide yes)
			)
		)
		(property "Author" "Antmicro"
			(at 107.95 81.28 0)
			(effects
				(font
					(size 1.27 1.27)
					(thickness 0.15)
				)
				(justify left bottom)
				(hide yes)
			)
		)
		(property "License" "Apache-2.0"
			(at 107.95 83.82 0)
			(effects
				(font
					(size 1.27 1.27)
					(thickness 0.15)
				)
				(justify left bottom)
				(hide yes)
			)
		)
		(pin "1"
		)
		(instances
			(project "environment-sensor"
				(path ""
					(reference "#PWR014")
					(unit 1)
				)
			)
		)
	)
	(symbol
		(lib_id "antmicropower:+3V3")
		(at 264.16 102.87 0)
		(mirror y)
		(unit 1)
		(exclude_from_sim no)
		(in_bom yes)
		(on_board yes)
		(dnp no)
		(fields_autoplaced yes)
		(property "Reference" "#PWR079"
			(at 264.16 106.68 0)
			(effects
				(font
					(size 1.27 1.27)
				)
				(hide yes)
			)
		)
		(property "Value" "+3V3"
			(at 264.16 97.79 0)
			(effects
				(font
					(size 1.27 1.27)
				)
			)
		)
		(property "Footprint" ""
			(at 264.16 102.87 0)
			(effects
				(font
					(size 1.27 1.27)
				)
				(hide yes)
			)
		)
		(property "Datasheet" ""
			(at 264.16 102.87 0)
			(effects
				(font
					(size 1.27 1.27)
				)
				(hide yes)
			)
		)
		(property "Description" ""
			(at 264.16 102.87 0)
			(effects
				(font
					(size 1.27 1.27)
				)
				(hide yes)
			)
		)
		(property "Author" "Antmicro"
			(at 248.92 105.41 0)
			(effects
				(font
					(size 1.27 1.27)
					(thickness 0.15)
				)
				(justify left bottom)
				(hide yes)
			)
		)
		(property "License" "Apache-2.0"
			(at 248.92 107.95 0)
			(effects
				(font
					(size 1.27 1.27)
					(thickness 0.15)
				)
				(justify left bottom)
				(hide yes)
			)
		)
		(pin "1"
		)
		(instances
			(project "environment-sensor"
				(path ""
					(reference "#PWR079")
					(unit 1)
				)
			)
		)
	)
	(symbol
		(lib_id "antmicroInterfaceControllers:FT232R_QFN")
		(at 71.12 177.8 0)
		(unit 1)
		(exclude_from_sim no)
		(in_bom yes)
		(on_board yes)
		(dnp no)
		(fields_autoplaced yes)
		(property "Reference" "U1"
			(at 83.82 170.18 0)
			(effects
				(font
					(size 1.27 1.27)
					(thickness 0.15)
				)
			)
		)
		(property "Value" "FT232R_QFN"
			(at 83.82 172.72 0)
			(effects
				(font
					(size 1.27 1.27)
					(thickness 0.15)
				)
			)
		)
		(property "Footprint" "antmicro-footprints:QFN-32-1EP_5x5mm"
			(at 111.76 187.96 0)
			(effects
				(font
					(size 1.27 1.27)
					(thickness 0.15)
				)
				(justify left bottom)
				(hide yes)
			)
		)
		(property "Datasheet" "https://www.ftdichip.com/Support/Documents/DataSheets/ICs/DS_FT232R.pdf"
			(at 111.76 190.5 0)
			(effects
				(font
					(size 1.27 1.27)
					(thickness 0.15)
				)
				(justify left bottom)
				(hide yes)
			)
		)
		(property "Description" "Interface Bridges, USB to UART, 1.8 V, 5.25 V, QFN, 32 Pins, -40 °C"
			(at 71.12 177.8 0)
			(effects
				(font
					(size 1.27 1.27)
				)
				(hide yes)
			)
		)
		(property "Manufacturer" "FTDI Chip"
			(at 111.76 193.04 0)
			(effects
				(font
					(size 1.27 1.27)
					(thickness 0.15)
				)
				(justify left bottom)
				(hide yes)
			)
		)
		(property "MPN" "FT232RQ-REEL"
			(at 111.76 195.58 0)
			(effects
				(font
					(size 1.27 1.27)
					(thickness 0.15)
				)
				(justify left bottom)
				(hide yes)
			)
		)
		(property "Author" "Antmicro"
			(at 111.76 198.12 0)
			(effects
				(font
					(size 1.27 1.27)
					(thickness 0.15)
				)
				(justify left bottom)
				(hide yes)
			)
		)
		(property "License" "Apache-2.0"
			(at 111.76 200.66 0)
			(effects
				(font
					(size 1.27 1.27)
					(thickness 0.15)
				)
				(justify left bottom)
				(hide yes)
			)
		)
		(pin "12"
		)
		(pin "31"
		)
		(pin "32"
		)
		(pin "33"
		)
		(pin "7"
		)
		(pin "30"
		)
		(pin "24"
		)
		(pin "22"
		)
		(pin "23"
		)
		(pin "27"
		)
		(pin "20"
		)
		(pin "28"
		)
		(pin "5"
		)
		(pin "25"
		)
		(pin "19"
		)
		(pin "26"
		)
		(pin "1"
		)
		(pin "2"
		)
		(pin "18"
		)
		(pin "17"
		)
		(pin "21"
		)
		(pin "15"
		)
		(pin "3"
		)
		(pin "8"
		)
		(pin "11"
		)
		(pin "13"
		)
		(pin "14"
		)
		(pin "4"
		)
		(pin "16"
		)
		(pin "29"
		)
		(pin "9"
		)
		(pin "10"
		)
		(pin "6"
		)
		(instances
			(project "environment-sensor"
				(path ""
					(reference "U1")
					(unit 1)
				)
			)
		)
	)
	(symbol
		(lib_id "antmicroCapacitors0402:C_16p_0402")
		(at 205.74 210.82 270)
		(unit 1)
		(exclude_from_sim no)
		(in_bom yes)
		(on_board yes)
		(dnp no)
		(fields_autoplaced yes)
		(property "Reference" "C14"
			(at 208.28 212.0962 90)
			(effects
				(font
					(size 1.27 1.27)
					(thickness 0.15)
				)
				(justify left)
			)
		)
		(property "Value" "C_16p_0402"
			(at 195.58 231.14 0)
			(effects
				(font
					(size 1.27 1.27)
					(thickness 0.15)
				)
				(justify left bottom)
				(hide yes)
			)
		)
		(property "Footprint" "antmicro-footprints:C_0402_1005Metric"
			(at 193.04 231.14 0)
			(effects
				(font
					(size 1.27 1.27)
					(thickness 0.15)
				)
				(justify left bottom)
				(hide yes)
			)
		)
		(property "Datasheet" "https://www.passivecomponent.com/wp-content/uploads/datasheet/WTC_MLCC_General_Purpose.pdf"
			(at 190.5 231.14 0)
			(effects
				(font
					(size 1.27 1.27)
					(thickness 0.15)
				)
				(justify left bottom)
				(hide yes)
			)
		)
		(property "Description" "SMD Multilayer Ceramic Capacitor, General Purpose, 16 pF, 50 V, 0402 [1005 Metric], ± 5%, C0G / NP0"
			(at 205.74 210.82 0)
			(effects
				(font
					(size 1.27 1.27)
				)
				(hide yes)
			)
		)
		(property "Manufacturer" "Walsin"
			(at 185.42 231.14 0)
			(effects
				(font
					(size 1.27 1.27)
					(thickness 0.15)
				)
				(justify left bottom)
				(hide yes)
			)
		)
		(property "MPN" "0402N160J500CT"
			(at 187.96 231.14 0)
			(effects
				(font
					(size 1.27 1.27)
					(thickness 0.15)
				)
				(justify left bottom)
				(hide yes)
			)
		)
		(property "Val" "16p"
			(at 208.28 214.6362 90)
			(effects
				(font
					(size 1.27 1.27)
					(thickness 0.15)
				)
				(justify left)
			)
		)
		(property "License" "Apache-2.0"
			(at 182.88 231.14 0)
			(effects
				(font
					(size 1.27 1.27)
					(thickness 0.15)
				)
				(justify left bottom)
				(hide yes)
			)
		)
		(property "Author" "Antmicro"
			(at 180.34 231.14 0)
			(effects
				(font
					(size 1.27 1.27)
					(thickness 0.15)
				)
				(justify left bottom)
				(hide yes)
			)
		)
		(property "Voltage" ""
			(at 177.8 231.14 0)
			(effects
				(font
					(size 1.27 1.27)
				)
				(justify left bottom)
				(hide yes)
			)
		)
		(property "Dielectric" ""
			(at 175.26 231.14 0)
			(effects
				(font
					(size 1.27 1.27)
				)
				(justify left bottom)
				(hide yes)
			)
		)
		(property "Public" "False"
			(at 172.72 231.14 0)
			(effects
				(font
					(size 1.27 1.27)
				)
				(justify left bottom)
				(hide yes)
			)
		)
		(pin "1"
		)
		(pin "2"
		)
		(instances
			(project "environment-sensor"
				(path ""
					(reference "C14")
					(unit 1)
				)
			)
		)
	)
	(symbol
		(lib_id "antmicropower:GND")
		(at 353.06 240.03 0)
		(mirror y)
		(unit 1)
		(exclude_from_sim no)
		(in_bom yes)
		(on_board yes)
		(dnp no)
		(fields_autoplaced yes)
		(property "Reference" "#PWR065"
			(at 353.06 246.38 0)
			(effects
				(font
					(size 1.27 1.27)
				)
				(hide yes)
			)
		)
		(property "Value" "GND"
			(at 353.06 245.11 0)
			(effects
				(font
					(size 1.27 1.27)
				)
			)
		)
		(property "Footprint" ""
			(at 353.06 240.03 0)
			(effects
				(font
					(size 1.27 1.27)
				)
				(hide yes)
			)
		)
		(property "Datasheet" ""
			(at 353.06 240.03 0)
			(effects
				(font
					(size 1.27 1.27)
				)
				(hide yes)
			)
		)
		(property "Description" ""
			(at 353.06 240.03 0)
			(effects
				(font
					(size 1.27 1.27)
				)
				(hide yes)
			)
		)
		(property "Author" "Antmicro"
			(at 344.17 247.65 0)
			(effects
				(font
					(size 1.27 1.27)
					(thickness 0.15)
				)
				(justify left bottom)
				(hide yes)
			)
		)
		(property "License" "Apache-2.0"
			(at 344.17 250.19 0)
			(effects
				(font
					(size 1.27 1.27)
					(thickness 0.15)
				)
				(justify left bottom)
				(hide yes)
			)
		)
		(pin "1"
		)
		(instances
			(project "environment-sensor"
				(path ""
					(reference "#PWR065")
					(unit 1)
				)
			)
		)
	)
	(symbol
		(lib_id "antmicropower:GND")
		(at 289.56 118.11 0)
		(mirror y)
		(unit 1)
		(exclude_from_sim no)
		(in_bom yes)
		(on_board yes)
		(dnp no)
		(fields_autoplaced yes)
		(property "Reference" "#PWR027"
			(at 289.56 124.46 0)
			(effects
				(font
					(size 1.27 1.27)
				)
				(hide yes)
			)
		)
		(property "Value" "GND"
			(at 289.56 123.19 0)
			(effects
				(font
					(size 1.27 1.27)
				)
			)
		)
		(property "Footprint" ""
			(at 289.56 118.11 0)
			(effects
				(font
					(size 1.27 1.27)
				)
				(hide yes)
			)
		)
		(property "Datasheet" ""
			(at 289.56 118.11 0)
			(effects
				(font
					(size 1.27 1.27)
				)
				(hide yes)
			)
		)
		(property "Description" ""
			(at 289.56 118.11 0)
			(effects
				(font
					(size 1.27 1.27)
				)
				(hide yes)
			)
		)
		(property "Author" "Antmicro"
			(at 280.67 125.73 0)
			(effects
				(font
					(size 1.27 1.27)
					(thickness 0.15)
				)
				(justify left bottom)
				(hide yes)
			)
		)
		(property "License" "Apache-2.0"
			(at 280.67 128.27 0)
			(effects
				(font
					(size 1.27 1.27)
					(thickness 0.15)
				)
				(justify left bottom)
				(hide yes)
			)
		)
		(pin "1"
		)
		(instances
			(project "environment-sensor"
				(path ""
					(reference "#PWR027")
					(unit 1)
				)
			)
		)
	)
	(symbol
		(lib_id "antmicroUSBConnectors:USB-C_GCT_USB4105-GF-A")
		(at 44.45 33.02 0)
		(unit 1)
		(exclude_from_sim no)
		(in_bom yes)
		(on_board yes)
		(dnp no)
		(fields_autoplaced yes)
		(property "Reference" "J1"
			(at 31.115 25.4 0)
			(effects
				(font
					(size 1.27 1.27)
					(thickness 0.15)
				)
			)
		)
		(property "Value" "USB-C_GCT_USB4105-GF-A"
			(at 31.115 27.94 0)
			(effects
				(font
					(size 1.27 1.27)
					(thickness 0.15)
				)
				(hide yes)
			)
		)
		(property "Footprint" "antmicro-footprints:USB-C_Receptacle_GCT_USB4105-GF-A"
			(at 82.55 40.64 0)
			(effects
				(font
					(size 1.27 1.27)
					(thickness 0.15)
				)
				(justify left bottom)
				(hide yes)
			)
		)
		(property "Datasheet" "https://gct.co/files/drawings/usb4105.pdf"
			(at 82.55 43.18 0)
			(effects
				(font
					(size 1.27 1.27)
					(thickness 0.15)
				)
				(justify left bottom)
				(hide yes)
			)
		)
		(property "Description" "USB-C (USB TYPE-C) USB 2.0 Receptacle Connector 24 (16+8 Dummy) Position Surface Mount, Right Angle"
			(at 44.45 33.02 0)
			(effects
				(font
					(size 1.27 1.27)
				)
				(hide yes)
			)
		)
		(property "Manufacturer" "GCT"
			(at 82.55 45.72 0)
			(effects
				(font
					(size 1.27 1.27)
					(thickness 0.15)
				)
				(justify left bottom)
				(hide yes)
			)
		)
		(property "MPN" "USB4105-GF-A"
			(at 82.55 48.26 0)
			(effects
				(font
					(size 1.27 1.27)
					(thickness 0.15)
				)
				(justify left bottom)
			)
		)
		(property "Author" "Antmicro"
			(at 82.55 50.8 0)
			(effects
				(font
					(size 1.27 1.27)
					(thickness 0.15)
				)
				(justify left bottom)
				(hide yes)
			)
		)
		(property "License" "Apache-2.0"
			(at 82.55 53.34 0)
			(effects
				(font
					(size 1.27 1.27)
					(thickness 0.15)
				)
				(justify left bottom)
				(hide yes)
			)
		)
		(pin "B12"
		)
		(pin "B7"
		)
		(pin "SH"
		)
		(pin "B9"
		)
		(pin "B6"
		)
		(pin "B8"
		)
		(pin "A9"
		)
		(pin "A12"
		)
		(pin "B4"
		)
		(pin "B5"
		)
		(pin "A4"
		)
		(pin "A1"
		)
		(pin "B1"
		)
		(pin "A5"
		)
		(pin "A7"
		)
		(pin "A8"
		)
		(pin "A6"
		)
		(instances
			(project "environment-sensor"
				(path ""
					(reference "J1")
					(unit 1)
				)
			)
		)
	)
	(symbol
		(lib_id "antmicropower:+3V3")
		(at 316.23 30.48 0)
		(mirror y)
		(unit 1)
		(exclude_from_sim no)
		(in_bom yes)
		(on_board yes)
		(dnp no)
		(fields_autoplaced yes)
		(property "Reference" "#PWR059"
			(at 316.23 34.29 0)
			(effects
				(font
					(size 1.27 1.27)
				)
				(hide yes)
			)
		)
		(property "Value" "+3V3"
			(at 316.23 25.4 0)
			(effects
				(font
					(size 1.27 1.27)
				)
			)
		)
		(property "Footprint" ""
			(at 316.23 30.48 0)
			(effects
				(font
					(size 1.27 1.27)
				)
				(hide yes)
			)
		)
		(property "Datasheet" ""
			(at 316.23 30.48 0)
			(effects
				(font
					(size 1.27 1.27)
				)
				(hide yes)
			)
		)
		(property "Description" ""
			(at 316.23 30.48 0)
			(effects
				(font
					(size 1.27 1.27)
				)
				(hide yes)
			)
		)
		(property "Author" "Antmicro"
			(at 300.99 33.02 0)
			(effects
				(font
					(size 1.27 1.27)
					(thickness 0.15)
				)
				(justify left bottom)
				(hide yes)
			)
		)
		(property "License" "Apache-2.0"
			(at 300.99 35.56 0)
			(effects
				(font
					(size 1.27 1.27)
					(thickness 0.15)
				)
				(justify left bottom)
				(hide yes)
			)
		)
		(pin "1"
		)
		(instances
			(project "environment-sensor"
				(path ""
					(reference "#PWR059")
					(unit 1)
				)
			)
		)
	)
	(symbol
		(lib_id "antmicropower:+3V3")
		(at 388.62 35.56 0)
		(unit 1)
		(exclude_from_sim no)
		(in_bom yes)
		(on_board yes)
		(dnp no)
		(fields_autoplaced yes)
		(property "Reference" "#PWR077"
			(at 388.62 39.37 0)
			(effects
				(font
					(size 1.27 1.27)
				)
				(hide yes)
			)
		)
		(property "Value" "+3V3"
			(at 388.62 30.48 0)
			(effects
				(font
					(size 1.27 1.27)
				)
			)
		)
		(property "Footprint" ""
			(at 388.62 35.56 0)
			(effects
				(font
					(size 1.27 1.27)
				)
				(hide yes)
			)
		)
		(property "Datasheet" ""
			(at 388.62 35.56 0)
			(effects
				(font
					(size 1.27 1.27)
				)
				(hide yes)
			)
		)
		(property "Description" ""
			(at 388.62 35.56 0)
			(effects
				(font
					(size 1.27 1.27)
				)
				(hide yes)
			)
		)
		(property "Author" "Antmicro"
			(at 403.86 38.1 0)
			(effects
				(font
					(size 1.27 1.27)
					(thickness 0.15)
				)
				(justify left bottom)
				(hide yes)
			)
		)
		(property "License" "Apache-2.0"
			(at 403.86 40.64 0)
			(effects
				(font
					(size 1.27 1.27)
					(thickness 0.15)
				)
				(justify left bottom)
				(hide yes)
			)
		)
		(pin "1"
		)
		(instances
			(project "environment-sensor"
				(path ""
					(reference "#PWR077")
					(unit 1)
				)
			)
		)
	)
	(symbol
		(lib_id "antmicroResistors0402:R_100k_0402")
		(at 336.55 161.29 270)
		(unit 1)
		(exclude_from_sim no)
		(in_bom no)
		(on_board yes)
		(dnp yes)
		(fields_autoplaced yes)
		(property "Reference" "R35"
			(at 330.2 162.56 90)
			(effects
				(font
					(size 1.27 1.27)
					(thickness 0.15)
				)
				(justify left)
			)
		)
		(property "Value" "R_100k_0402"
			(at 323.85 181.61 0)
			(effects
				(font
					(size 1.27 1.27)
					(thickness 0.15)
				)
				(justify left bottom)
				(hide yes)
			)
		)
		(property "Footprint" "antmicro-footprints:R_0402_1005Metric"
			(at 321.31 181.61 0)
			(effects
				(font
					(size 1.27 1.27)
					(thickness 0.15)
				)
				(justify left bottom)
				(hide yes)
			)
		)
		(property "Datasheet" "https://www.bourns.com/docs/product-datasheets/cr.pdf"
			(at 318.77 181.61 0)
			(effects
				(font
					(size 1.27 1.27)
					(thickness 0.15)
				)
				(justify left bottom)
				(hide yes)
			)
		)
		(property "Description" "SMD Chip Resistor, 100 kohm, ± 1%, 62.5 mW, 0402 [1005 Metric], Thick Film, General Purpose"
			(at 336.55 161.29 0)
			(effects
				(font
					(size 1.27 1.27)
				)
				(hide yes)
			)
		)
		(property "Manufacturer" "Bourns"
			(at 313.69 181.61 0)
			(effects
				(font
					(size 1.27 1.27)
					(thickness 0.15)
				)
				(justify left bottom)
				(hide yes)
			)
		)
		(property "MPN" "CR0402-FX-1003GLF"
			(at 316.23 181.61 0)
			(effects
				(font
					(size 1.27 1.27)
					(thickness 0.15)
				)
				(justify left bottom)
				(hide yes)
			)
		)
		(property "Val" "100k"
			(at 330.2 165.1 90)
			(effects
				(font
					(size 1.27 1.27)
					(thickness 0.15)
				)
				(justify left)
			)
		)
		(property "License" "Apache-2.0"
			(at 311.15 181.61 0)
			(effects
				(font
					(size 1.27 1.27)
					(thickness 0.15)
				)
				(justify left bottom)
				(hide yes)
			)
		)
		(property "Author" "Antmicro"
			(at 308.61 181.61 0)
			(effects
				(font
					(size 1.27 1.27)
					(thickness 0.15)
				)
				(justify left bottom)
				(hide yes)
			)
		)
		(property "Tolerance" "1%"
			(at 326.39 181.61 0)
			(effects
				(font
					(size 1.27 1.27)
				)
				(justify left bottom)
				(hide yes)
			)
		)
		(property "Public" "False"
			(at 306.07 181.61 0)
			(effects
				(font
					(size 1.27 1.27)
				)
				(justify left bottom)
				(hide yes)
			)
		)
		(pin "1"
		)
		(pin "2"
		)
		(instances
			(project "environment-sensor"
				(path ""
					(reference "R35")
					(unit 1)
				)
			)
		)
	)
	(symbol
		(lib_id "antmicropower:GND")
		(at 251.46 118.11 0)
		(mirror y)
		(unit 1)
		(exclude_from_sim no)
		(in_bom yes)
		(on_board yes)
		(dnp no)
		(fields_autoplaced yes)
		(property "Reference" "#PWR040"
			(at 251.46 124.46 0)
			(effects
				(font
					(size 1.27 1.27)
				)
				(hide yes)
			)
		)
		(property "Value" "GND"
			(at 247.65 120.65 0)
			(effects
				(font
					(size 1.27 1.27)
				)
			)
		)
		(property "Footprint" ""
			(at 251.46 118.11 0)
			(effects
				(font
					(size 1.27 1.27)
				)
				(hide yes)
			)
		)
		(property "Datasheet" ""
			(at 251.46 118.11 0)
			(effects
				(font
					(size 1.27 1.27)
				)
				(hide yes)
			)
		)
		(property "Description" ""
			(at 251.46 118.11 0)
			(effects
				(font
					(size 1.27 1.27)
				)
				(hide yes)
			)
		)
		(property "Author" "Antmicro"
			(at 242.57 125.73 0)
			(effects
				(font
					(size 1.27 1.27)
					(thickness 0.15)
				)
				(justify left bottom)
				(hide yes)
			)
		)
		(property "License" "Apache-2.0"
			(at 242.57 128.27 0)
			(effects
				(font
					(size 1.27 1.27)
					(thickness 0.15)
				)
				(justify left bottom)
				(hide yes)
			)
		)
		(pin "1"
		)
		(instances
			(project "environment-sensor"
				(path ""
					(reference "#PWR040")
					(unit 1)
				)
			)
		)
	)
	(symbol
		(lib_id "antmicropower:+3V3")
		(at 378.46 151.13 0)
		(mirror y)
		(unit 1)
		(exclude_from_sim no)
		(in_bom yes)
		(on_board yes)
		(dnp no)
		(fields_autoplaced yes)
		(property "Reference" "#PWR072"
			(at 378.46 154.94 0)
			(effects
				(font
					(size 1.27 1.27)
				)
				(hide yes)
			)
		)
		(property "Value" "+3V3"
			(at 378.46 146.05 0)
			(effects
				(font
					(size 1.27 1.27)
				)
			)
		)
		(property "Footprint" ""
			(at 378.46 151.13 0)
			(effects
				(font
					(size 1.27 1.27)
				)
				(hide yes)
			)
		)
		(property "Datasheet" ""
			(at 378.46 151.13 0)
			(effects
				(font
					(size 1.27 1.27)
				)
				(hide yes)
			)
		)
		(property "Description" ""
			(at 378.46 151.13 0)
			(effects
				(font
					(size 1.27 1.27)
				)
				(hide yes)
			)
		)
		(property "Author" "Antmicro"
			(at 363.22 153.67 0)
			(effects
				(font
					(size 1.27 1.27)
					(thickness 0.15)
				)
				(justify left bottom)
				(hide yes)
			)
		)
		(property "License" "Apache-2.0"
			(at 363.22 156.21 0)
			(effects
				(font
					(size 1.27 1.27)
					(thickness 0.15)
				)
				(justify left bottom)
				(hide yes)
			)
		)
		(pin "1"
		)
		(instances
			(project "environment-sensor"
				(path ""
					(reference "#PWR072")
					(unit 1)
				)
			)
		)
	)
	(symbol
		(lib_id "antmicropower:GND")
		(at 240.03 194.31 0)
		(mirror y)
		(unit 1)
		(exclude_from_sim no)
		(in_bom yes)
		(on_board yes)
		(dnp no)
		(fields_autoplaced yes)
		(property "Reference" "#PWR042"
			(at 240.03 200.66 0)
			(effects
				(font
					(size 1.27 1.27)
				)
				(hide yes)
			)
		)
		(property "Value" "GND"
			(at 240.03 199.39 0)
			(effects
				(font
					(size 1.27 1.27)
				)
			)
		)
		(property "Footprint" ""
			(at 240.03 194.31 0)
			(effects
				(font
					(size 1.27 1.27)
				)
				(hide yes)
			)
		)
		(property "Datasheet" ""
			(at 240.03 194.31 0)
			(effects
				(font
					(size 1.27 1.27)
				)
				(hide yes)
			)
		)
		(property "Description" ""
			(at 240.03 194.31 0)
			(effects
				(font
					(size 1.27 1.27)
				)
				(hide yes)
			)
		)
		(property "Author" "Antmicro"
			(at 231.14 201.93 0)
			(effects
				(font
					(size 1.27 1.27)
					(thickness 0.15)
				)
				(justify left bottom)
				(hide yes)
			)
		)
		(property "License" "Apache-2.0"
			(at 231.14 204.47 0)
			(effects
				(font
					(size 1.27 1.27)
					(thickness 0.15)
				)
				(justify left bottom)
				(hide yes)
			)
		)
		(pin "1"
		)
		(instances
			(project "environment-sensor"
				(path ""
					(reference "#PWR042")
					(unit 1)
				)
			)
		)
	)
	(symbol
		(lib_id "antmicroCapacitors0402:C_100n_0402")
		(at 276.86 116.84 90)
		(unit 1)
		(exclude_from_sim no)
		(in_bom yes)
		(on_board yes)
		(dnp no)
		(fields_autoplaced yes)
		(property "Reference" "C12"
			(at 274.32 113.0235 90)
			(effects
				(font
					(size 1.27 1.27)
					(thickness 0.15)
				)
				(justify left)
			)
		)
		(property "Value" "C_100n_0402"
			(at 287.02 96.52 0)
			(effects
				(font
					(size 1.27 1.27)
					(thickness 0.15)
				)
				(justify left bottom)
				(hide yes)
			)
		)
		(property "Footprint" "antmicro-footprints:C_0402_1005Metric"
			(at 289.56 96.52 0)
			(effects
				(font
					(size 1.27 1.27)
					(thickness 0.15)
				)
				(justify left bottom)
				(hide yes)
			)
		)
		(property "Datasheet" "https://www.murata.com/products/productdetail?partno=GRM155R61H104KE14%23"
			(at 292.1 96.52 0)
			(effects
				(font
					(size 1.27 1.27)
					(thickness 0.15)
				)
				(justify left bottom)
				(hide yes)
			)
		)
		(property "Description" "SMD Multilayer Ceramic Capacitor, 0.1 µF, 50 V, 0402 [1005 Metric], ± 10%, X5R, GRM Series"
			(at 276.86 116.84 0)
			(effects
				(font
					(size 1.27 1.27)
				)
				(hide yes)
			)
		)
		(property "Manufacturer" "Murata"
			(at 297.18 96.52 0)
			(effects
				(font
					(size 1.27 1.27)
					(thickness 0.15)
				)
				(justify left bottom)
				(hide yes)
			)
		)
		(property "MPN" "GRM155R61H104KE14D"
			(at 294.64 96.52 0)
			(effects
				(font
					(size 1.27 1.27)
					(thickness 0.15)
				)
				(justify left bottom)
				(hide yes)
			)
		)
		(property "Val" "100n"
			(at 274.32 115.5635 90)
			(effects
				(font
					(size 1.27 1.27)
					(thickness 0.15)
				)
				(justify left)
			)
		)
		(property "License" "Apache-2.0"
			(at 299.72 96.52 0)
			(effects
				(font
					(size 1.27 1.27)
					(thickness 0.15)
				)
				(justify left bottom)
				(hide yes)
			)
		)
		(property "Author" "Antmicro"
			(at 302.26 96.52 0)
			(effects
				(font
					(size 1.27 1.27)
					(thickness 0.15)
				)
				(justify left bottom)
				(hide yes)
			)
		)
		(property "Voltage" "50V"
			(at 304.8 96.52 0)
			(effects
				(font
					(size 1.27 1.27)
				)
				(justify left bottom)
				(hide yes)
			)
		)
		(property "Dielectric" "X5R"
			(at 307.34 96.52 0)
			(effects
				(font
					(size 1.27 1.27)
				)
				(justify left bottom)
				(hide yes)
			)
		)
		(property "Public" "False"
			(at 309.88 96.52 0)
			(effects
				(font
					(size 1.27 1.27)
				)
				(justify left bottom)
				(hide yes)
			)
		)
		(pin "1"
		)
		(pin "2"
		)
		(instances
			(project "environment-sensor"
				(path ""
					(reference "C12")
					(unit 1)
				)
			)
		)
	)
	(symbol
		(lib_id "antmicroPMICVoltageRegulatorsLinear:AP7370-33SA-7")
		(at 170.18 46.99 0)
		(unit 1)
		(exclude_from_sim no)
		(in_bom yes)
		(on_board yes)
		(dnp no)
		(fields_autoplaced yes)
		(property "Reference" "U2"
			(at 177.8 40.64 0)
			(effects
				(font
					(size 1.27 1.27)
					(thickness 0.15)
				)
			)
		)
		(property "Value" "AP7370-33SA-7"
			(at 177.8 43.18 0)
			(effects
				(font
					(size 1.27 1.27)
					(thickness 0.15)
				)
			)
		)
		(property "Footprint" "antmicro-footprints:SOT-23-3"
			(at 200.66 57.15 0)
			(effects
				(font
					(size 1.27 1.27)
					(thickness 0.15)
				)
				(justify left bottom)
				(hide yes)
			)
		)
		(property "Datasheet" "https://www.diodes.com/assets/Datasheets/AP7370.pdf"
			(at 200.66 59.69 0)
			(effects
				(font
					(size 1.27 1.27)
					(thickness 0.15)
				)
				(justify left bottom)
				(hide yes)
			)
		)
		(property "Description" "Voltage regulator"
			(at 170.18 46.99 0)
			(effects
				(font
					(size 1.27 1.27)
				)
				(hide yes)
			)
		)
		(property "MPN" "AP7370-33SA-7"
			(at 200.66 62.23 0)
			(effects
				(font
					(size 1.27 1.27)
					(thickness 0.15)
				)
				(justify left bottom)
				(hide yes)
			)
		)
		(property "Manufacturer" "Diodes Incorporated"
			(at 200.66 64.77 0)
			(effects
				(font
					(size 1.27 1.27)
					(thickness 0.15)
				)
				(justify left bottom)
				(hide yes)
			)
		)
		(property "Author" "Antmicro"
			(at 200.66 67.31 0)
			(effects
				(font
					(size 1.27 1.27)
					(thickness 0.15)
				)
				(justify left bottom)
				(hide yes)
			)
		)
		(property "License" "Apache-2.0"
			(at 200.66 69.85 0)
			(effects
				(font
					(size 1.27 1.27)
					(thickness 0.15)
				)
				(justify left bottom)
				(hide yes)
			)
		)
		(pin "1"
		)
		(pin "2"
		)
		(pin "3"
		)
		(instances
			(project "environment-sensor"
				(path ""
					(reference "U2")
					(unit 1)
				)
			)
		)
	)
	(symbol
		(lib_id "antmicroTVSDiodes:ESD9X5.0ST5G")
		(at 93.98 114.3 90)
		(unit 1)
		(exclude_from_sim no)
		(in_bom yes)
		(on_board yes)
		(dnp no)
		(fields_autoplaced yes)
		(property "Reference" "D3"
			(at 97.79 108.9024 90)
			(effects
				(font
					(size 1.27 1.27)
					(thickness 0.15)
				)
				(justify right)
			)
		)
		(property "Value" "ESD9X5.0ST5G"
			(at 97.79 111.4424 90)
			(effects
				(font
					(size 1.27 1.27)
					(thickness 0.15)
				)
				(justify right)
			)
		)
		(property "Footprint" "antmicro-footprints:SOD-923"
			(at 101.6 92.71 0)
			(effects
				(font
					(size 1.27 1.27)
					(thickness 0.15)
				)
				(justify left bottom)
				(hide yes)
			)
		)
		(property "Datasheet" "https://www.onsemi.com/pdf/datasheet/esd9x3.3st5g-d.pdf"
			(at 104.14 92.71 0)
			(effects
				(font
					(size 1.27 1.27)
					(thickness 0.15)
				)
				(justify left bottom)
				(hide yes)
			)
		)
		(property "Description" "Unidirectional TVS, 30 kV,  SOD-923, 5 V, 65 pF"
			(at 93.98 114.3 0)
			(effects
				(font
					(size 1.27 1.27)
				)
				(hide yes)
			)
		)
		(property "Manufacturer" "ON Semiconductor"
			(at 106.68 92.71 0)
			(effects
				(font
					(size 1.27 1.27)
					(thickness 0.15)
				)
				(justify left bottom)
				(hide yes)
			)
		)
		(property "MPN" "ESD9X5.0ST5G"
			(at 109.22 92.71 0)
			(effects
				(font
					(size 1.27 1.27)
					(thickness 0.15)
				)
				(justify left bottom)
				(hide yes)
			)
		)
		(property "Author" "Antmicro"
			(at 111.76 92.71 0)
			(effects
				(font
					(size 1.27 1.27)
					(thickness 0.15)
				)
				(justify left bottom)
				(hide yes)
			)
		)
		(property "License" "Apache-2.0"
			(at 114.3 92.71 0)
			(effects
				(font
					(size 1.27 1.27)
					(thickness 0.15)
				)
				(justify left bottom)
				(hide yes)
			)
		)
		(property "Public" "False"
			(at 111.76 93.98 0)
			(effects
				(font
					(size 1.27 1.27)
				)
				(justify left bottom)
				(hide yes)
			)
		)
		(pin "1"
		)
		(pin "2"
		)
		(instances
			(project "environment-sensor"
				(path ""
					(reference "D3")
					(unit 1)
				)
			)
		)
	)
	(symbol
		(lib_id "antmicropower:GND")
		(at 227.33 273.05 0)
		(mirror y)
		(unit 1)
		(exclude_from_sim no)
		(in_bom yes)
		(on_board yes)
		(dnp no)
		(fields_autoplaced yes)
		(property "Reference" "#PWR035"
			(at 227.33 279.4 0)
			(effects
				(font
					(size 1.27 1.27)
				)
				(hide yes)
			)
		)
		(property "Value" "GND"
			(at 227.33 278.13 0)
			(effects
				(font
					(size 1.27 1.27)
				)
			)
		)
		(property "Footprint" ""
			(at 227.33 273.05 0)
			(effects
				(font
					(size 1.27 1.27)
				)
				(hide yes)
			)
		)
		(property "Datasheet" ""
			(at 227.33 273.05 0)
			(effects
				(font
					(size 1.27 1.27)
				)
				(hide yes)
			)
		)
		(property "Description" ""
			(at 227.33 273.05 0)
			(effects
				(font
					(size 1.27 1.27)
				)
				(hide yes)
			)
		)
		(property "Author" "Antmicro"
			(at 218.44 280.67 0)
			(effects
				(font
					(size 1.27 1.27)
					(thickness 0.15)
				)
				(justify left bottom)
				(hide yes)
			)
		)
		(property "License" "Apache-2.0"
			(at 218.44 283.21 0)
			(effects
				(font
					(size 1.27 1.27)
					(thickness 0.15)
				)
				(justify left bottom)
				(hide yes)
			)
		)
		(pin "1"
		)
		(instances
			(project "environment-sensor"
				(path ""
					(reference "#PWR035")
					(unit 1)
				)
			)
		)
	)
	(symbol
		(lib_id "antmicroTestPoints:TP_1.5mm_SMD")
		(at 147.32 260.35 180)
		(unit 1)
		(exclude_from_sim no)
		(in_bom yes)
		(on_board yes)
		(dnp no)
		(fields_autoplaced yes)
		(property "Reference" "TP5"
			(at 140.335 258.445 0)
			(effects
				(font
					(size 1.27 1.27)
					(thickness 0.15)
				)
			)
		)
		(property "Value" "TP_1.5mm_SMD"
			(at 132.08 252.73 0)
			(effects
				(font
					(size 1.27 1.27)
					(thickness 0.15)
				)
				(justify left bottom)
				(hide yes)
			)
		)
		(property "Footprint" "antmicro-footprints:TP_SMD_1.5mm"
			(at 132.08 250.19 0)
			(effects
				(font
					(size 1.27 1.27)
					(thickness 0.15)
				)
				(justify left bottom)
				(hide yes)
			)
		)
		(property "Datasheet" ""
			(at 132.08 247.65 0)
			(effects
				(font
					(size 1.27 1.27)
					(thickness 0.15)
				)
				(justify left bottom)
				(hide yes)
			)
		)
		(property "Description" "test point, SMT"
			(at 147.32 260.35 0)
			(effects
				(font
					(size 1.27 1.27)
				)
				(hide yes)
			)
		)
		(property "MPN" ""
			(at 147.32 260.35 0)
			(effects
				(font
					(size 1.27 1.27)
				)
				(hide yes)
			)
		)
		(property "Manufacturer" ""
			(at 147.32 260.35 0)
			(effects
				(font
					(size 1.27 1.27)
				)
				(hide yes)
			)
		)
		(property "Author" "Antmicro"
			(at 132.08 245.11 0)
			(effects
				(font
					(size 1.27 1.27)
					(thickness 0.15)
				)
				(justify left bottom)
				(hide yes)
			)
		)
		(property "License" "Apache-2.0"
			(at 132.08 242.57 0)
			(effects
				(font
					(size 1.27 1.27)
					(thickness 0.15)
				)
				(justify left bottom)
				(hide yes)
			)
		)
		(property "Public" "False"
			(at 132.08 240.03 0)
			(effects
				(font
					(size 1.27 1.27)
				)
				(justify left bottom)
				(hide yes)
			)
		)
		(pin "1"
		)
		(instances
			(project "environment-sensor"
				(path ""
					(reference "TP5")
					(unit 1)
				)
			)
		)
	)
	(symbol
		(lib_id "antmicroResistors0402:R_1k_0402")
		(at 62.23 182.88 0)
		(unit 1)
		(exclude_from_sim no)
		(in_bom yes)
		(on_board yes)
		(dnp no)
		(fields_autoplaced yes)
		(property "Reference" "R2"
			(at 60.96 184.15 0)
			(effects
				(font
					(size 1.27 1.27)
					(thickness 0.15)
				)
			)
		)
		(property "Value" "R_1k_0402"
			(at 82.55 195.58 0)
			(effects
				(font
					(size 1.27 1.27)
					(thickness 0.15)
				)
				(justify left bottom)
				(hide yes)
			)
		)
		(property "Footprint" "antmicro-footprints:R_0402_1005Metric"
			(at 82.55 198.12 0)
			(effects
				(font
					(size 1.27 1.27)
					(thickness 0.15)
				)
				(justify left bottom)
				(hide yes)
			)
		)
		(property "Datasheet" "https://www.bourns.com/docs/product-datasheets/cr.pdf"
			(at 82.55 200.66 0)
			(effects
				(font
					(size 1.27 1.27)
					(thickness 0.15)
				)
				(justify left bottom)
				(hide yes)
			)
		)
		(property "Description" "SMD Chip Resistor, 1 kohm, ± 1%, 63 mW, 0402 [1005 Metric], Thick Film, General Purpose"
			(at 62.23 182.88 0)
			(effects
				(font
					(size 1.27 1.27)
				)
				(hide yes)
			)
		)
		(property "Manufacturer" "Bourns"
			(at 82.55 205.74 0)
			(effects
				(font
					(size 1.27 1.27)
					(thickness 0.15)
				)
				(justify left bottom)
				(hide yes)
			)
		)
		(property "MPN" "CR0402-FX-1001GLF"
			(at 82.55 203.2 0)
			(effects
				(font
					(size 1.27 1.27)
					(thickness 0.15)
				)
				(justify left bottom)
				(hide yes)
			)
		)
		(property "Val" "1k"
			(at 68.58 184.15 0)
			(effects
				(font
					(size 1.27 1.27)
					(thickness 0.15)
				)
			)
		)
		(property "License" "Apache-2.0"
			(at 82.55 208.28 0)
			(effects
				(font
					(size 1.27 1.27)
					(thickness 0.15)
				)
				(justify left bottom)
				(hide yes)
			)
		)
		(property "Author" "Antmicro"
			(at 82.55 210.82 0)
			(effects
				(font
					(size 1.27 1.27)
					(thickness 0.15)
				)
				(justify left bottom)
				(hide yes)
			)
		)
		(property "Tolerance" "1%"
			(at 82.55 193.04 0)
			(effects
				(font
					(size 1.27 1.27)
				)
				(justify left bottom)
				(hide yes)
			)
		)
		(property "Public" "False"
			(at 82.55 213.36 0)
			(effects
				(font
					(size 1.27 1.27)
				)
				(justify left bottom)
				(hide yes)
			)
		)
		(pin "1"
		)
		(pin "2"
		)
		(instances
			(project "environment-sensor"
				(path ""
					(reference "R2")
					(unit 1)
				)
			)
		)
	)
	(symbol
		(lib_id "antmicroCapacitors0402:C_100n_0402")
		(at 161.29 60.96 270)
		(unit 1)
		(exclude_from_sim no)
		(in_bom yes)
		(on_board yes)
		(dnp no)
		(fields_autoplaced yes)
		(property "Reference" "C8"
			(at 163.83 62.2362 90)
			(effects
				(font
					(size 1.27 1.27)
					(thickness 0.15)
				)
				(justify left)
			)
		)
		(property "Value" "C_100n_0402"
			(at 151.13 81.28 0)
			(effects
				(font
					(size 1.27 1.27)
					(thickness 0.15)
				)
				(justify left bottom)
				(hide yes)
			)
		)
		(property "Footprint" "antmicro-footprints:C_0402_1005Metric"
			(at 148.59 81.28 0)
			(effects
				(font
					(size 1.27 1.27)
					(thickness 0.15)
				)
				(justify left bottom)
				(hide yes)
			)
		)
		(property "Datasheet" "https://www.murata.com/products/productdetail?partno=GRM155R61H104KE14%23"
			(at 146.05 81.28 0)
			(effects
				(font
					(size 1.27 1.27)
					(thickness 0.15)
				)
				(justify left bottom)
				(hide yes)
			)
		)
		(property "Description" "SMD Multilayer Ceramic Capacitor, 0.1 µF, 50 V, 0402 [1005 Metric], ± 10%, X5R, GRM Series"
			(at 161.29 60.96 0)
			(effects
				(font
					(size 1.27 1.27)
				)
				(hide yes)
			)
		)
		(property "Manufacturer" "Murata"
			(at 140.97 81.28 0)
			(effects
				(font
					(size 1.27 1.27)
					(thickness 0.15)
				)
				(justify left bottom)
				(hide yes)
			)
		)
		(property "MPN" "GRM155R61H104KE14D"
			(at 143.51 81.28 0)
			(effects
				(font
					(size 1.27 1.27)
					(thickness 0.15)
				)
				(justify left bottom)
				(hide yes)
			)
		)
		(property "Val" "100n"
			(at 163.83 64.7762 90)
			(effects
				(font
					(size 1.27 1.27)
					(thickness 0.15)
				)
				(justify left)
			)
		)
		(property "License" "Apache-2.0"
			(at 138.43 81.28 0)
			(effects
				(font
					(size 1.27 1.27)
					(thickness 0.15)
				)
				(justify left bottom)
				(hide yes)
			)
		)
		(property "Author" "Antmicro"
			(at 135.89 81.28 0)
			(effects
				(font
					(size 1.27 1.27)
					(thickness 0.15)
				)
				(justify left bottom)
				(hide yes)
			)
		)
		(property "Voltage" "50V"
			(at 133.35 81.28 0)
			(effects
				(font
					(size 1.27 1.27)
				)
				(justify left bottom)
				(hide yes)
			)
		)
		(property "Dielectric" "X5R"
			(at 130.81 81.28 0)
			(effects
				(font
					(size 1.27 1.27)
				)
				(justify left bottom)
				(hide yes)
			)
		)
		(property "Public" "False"
			(at 128.27 81.28 0)
			(effects
				(font
					(size 1.27 1.27)
				)
				(justify left bottom)
				(hide yes)
			)
		)
		(pin "1"
		)
		(pin "2"
		)
		(instances
			(project "environment-sensor"
				(path ""
					(reference "C8")
					(unit 1)
				)
			)
		)
	)
	(symbol
		(lib_id "antmicroResistors0402:R_100R_0402")
		(at 288.29 163.83 0)
		(unit 1)
		(exclude_from_sim no)
		(in_bom yes)
		(on_board yes)
		(dnp no)
		(fields_autoplaced yes)
		(property "Reference" "R28"
			(at 290.83 166.37 0)
			(effects
				(font
					(size 1.27 1.27)
					(thickness 0.15)
				)
			)
		)
		(property "Value" "R_100R_0402"
			(at 308.61 176.53 0)
			(effects
				(font
					(size 1.27 1.27)
					(thickness 0.15)
				)
				(justify left bottom)
				(hide yes)
			)
		)
		(property "Footprint" "antmicro-footprints:R_0402_1005Metric"
			(at 308.61 179.07 0)
			(effects
				(font
					(size 1.27 1.27)
					(thickness 0.15)
				)
				(justify left bottom)
				(hide yes)
			)
		)
		(property "Datasheet" "https://www.bourns.com/docs/product-datasheets/cr.pdf"
			(at 308.61 181.61 0)
			(effects
				(font
					(size 1.27 1.27)
					(thickness 0.15)
				)
				(justify left bottom)
				(hide yes)
			)
		)
		(property "Description" "SMD Chip Resistor, 100 ohm, ± 1%, 62.5 mW, 0402 [1005 Metric], Thick Film, General Purpose"
			(at 288.29 163.83 0)
			(effects
				(font
					(size 1.27 1.27)
				)
				(hide yes)
			)
		)
		(property "Manufacturer" "Bourns"
			(at 308.61 186.69 0)
			(effects
				(font
					(size 1.27 1.27)
					(thickness 0.15)
				)
				(justify left bottom)
				(hide yes)
			)
		)
		(property "MPN" "CR0402-FX-1000GLF"
			(at 308.61 184.15 0)
			(effects
				(font
					(size 1.27 1.27)
					(thickness 0.15)
				)
				(justify left bottom)
				(hide yes)
			)
		)
		(property "Val" "100R"
			(at 290.83 168.91 0)
			(effects
				(font
					(size 1.27 1.27)
					(thickness 0.15)
				)
			)
		)
		(property "License" "Apache-2.0"
			(at 308.61 189.23 0)
			(effects
				(font
					(size 1.27 1.27)
					(thickness 0.15)
				)
				(justify left bottom)
				(hide yes)
			)
		)
		(property "Author" "Antmicro"
			(at 308.61 191.77 0)
			(effects
				(font
					(size 1.27 1.27)
					(thickness 0.15)
				)
				(justify left bottom)
				(hide yes)
			)
		)
		(property "Tolerance" "1%"
			(at 308.61 173.99 0)
			(effects
				(font
					(size 1.27 1.27)
				)
				(justify left bottom)
				(hide yes)
			)
		)
		(property "Public" "False"
			(at 308.61 194.31 0)
			(effects
				(font
					(size 1.27 1.27)
				)
				(justify left bottom)
				(hide yes)
			)
		)
		(pin "1"
		)
		(pin "2"
		)
		(instances
			(project "environment-sensor"
				(path ""
					(reference "R28")
					(unit 1)
				)
			)
		)
	)
	(symbol
		(lib_id "antmicropower:GND")
		(at 382.27 123.19 0)
		(mirror y)
		(unit 1)
		(exclude_from_sim no)
		(in_bom yes)
		(on_board yes)
		(dnp no)
		(fields_autoplaced yes)
		(property "Reference" "#PWR074"
			(at 382.27 129.54 0)
			(effects
				(font
					(size 1.27 1.27)
				)
				(hide yes)
			)
		)
		(property "Value" "GND"
			(at 382.27 128.27 0)
			(effects
				(font
					(size 1.27 1.27)
				)
			)
		)
		(property "Footprint" ""
			(at 382.27 123.19 0)
			(effects
				(font
					(size 1.27 1.27)
				)
				(hide yes)
			)
		)
		(property "Datasheet" ""
			(at 382.27 123.19 0)
			(effects
				(font
					(size 1.27 1.27)
				)
				(hide yes)
			)
		)
		(property "Description" ""
			(at 382.27 123.19 0)
			(effects
				(font
					(size 1.27 1.27)
				)
				(hide yes)
			)
		)
		(property "Author" "Antmicro"
			(at 373.38 130.81 0)
			(effects
				(font
					(size 1.27 1.27)
					(thickness 0.15)
				)
				(justify left bottom)
				(hide yes)
			)
		)
		(property "License" "Apache-2.0"
			(at 373.38 133.35 0)
			(effects
				(font
					(size 1.27 1.27)
					(thickness 0.15)
				)
				(justify left bottom)
				(hide yes)
			)
		)
		(pin "1"
		)
		(instances
			(project "environment-sensor"
				(path ""
					(reference "#PWR074")
					(unit 1)
				)
			)
		)
	)
	(symbol
		(lib_id "antmicroResistors0402:R_0R_0402")
		(at 101.6 185.42 0)
		(unit 1)
		(exclude_from_sim no)
		(in_bom yes)
		(on_board yes)
		(dnp no)
		(fields_autoplaced yes)
		(property "Reference" "R5"
			(at 100.965 184.15 0)
			(effects
				(font
					(size 1.27 1.27)
					(thickness 0.15)
				)
			)
		)
		(property "Value" "R_0R_0402"
			(at 121.92 198.12 0)
			(effects
				(font
					(size 1.27 1.27)
					(thickness 0.15)
				)
				(justify left bottom)
				(hide yes)
			)
		)
		(property "Footprint" "antmicro-footprints:R_0402_1005Metric"
			(at 121.92 200.66 0)
			(effects
				(font
					(size 1.27 1.27)
					(thickness 0.15)
				)
				(justify left bottom)
				(hide yes)
			)
		)
		(property "Datasheet" "https://industrial.panasonic.com/cdbs/www-data/pdf/RDA0000/AOA0000C301.pdf"
			(at 121.92 203.2 0)
			(effects
				(font
					(size 1.27 1.27)
					(thickness 0.15)
				)
				(justify left bottom)
				(hide yes)
			)
		)
		(property "Description" "SMD Chip Resistor, Jumper, 0 ohm, 100 mW, 0402 [1005 Metric], Thick Film, General Purpose"
			(at 101.6 185.42 0)
			(effects
				(font
					(size 1.27 1.27)
				)
				(hide yes)
			)
		)
		(property "Manufacturer" "Panasonic"
			(at 121.92 208.28 0)
			(effects
				(font
					(size 1.27 1.27)
					(thickness 0.15)
				)
				(justify left bottom)
				(hide yes)
			)
		)
		(property "MPN" "ERJ2GE0R00X"
			(at 121.92 205.74 0)
			(effects
				(font
					(size 1.27 1.27)
					(thickness 0.15)
				)
				(justify left bottom)
				(hide yes)
			)
		)
		(property "Val" "0R"
			(at 107.315 184.15 0)
			(effects
				(font
					(size 1.27 1.27)
					(thickness 0.15)
				)
			)
		)
		(property "License" "Apache-2.0"
			(at 121.92 210.82 0)
			(effects
				(font
					(size 1.27 1.27)
					(thickness 0.15)
				)
				(justify left bottom)
				(hide yes)
			)
		)
		(property "Author" "Antmicro"
			(at 121.92 213.36 0)
			(effects
				(font
					(size 1.27 1.27)
					(thickness 0.15)
				)
				(justify left bottom)
				(hide yes)
			)
		)
		(property "Tolerance" "~"
			(at 121.92 195.58 0)
			(effects
				(font
					(size 1.27 1.27)
				)
				(justify left bottom)
				(hide yes)
			)
		)
		(property "Current" "1A"
			(at 104.14 185.42 0)
			(effects
				(font
					(size 1.27 1.27)
					(thickness 0.15)
				)
				(hide yes)
			)
		)
		(property "Public" "False"
			(at 121.92 215.9 0)
			(effects
				(font
					(size 1.27 1.27)
				)
				(justify left bottom)
				(hide yes)
			)
		)
		(pin "1"
		)
		(pin "2"
		)
		(instances
			(project "environment-sensor"
				(path ""
					(reference "R5")
					(unit 1)
				)
			)
		)
	)
	(symbol
		(lib_id "antmicroResistors0402:R_1M_0402")
		(at 209.55 208.28 0)
		(unit 1)
		(exclude_from_sim no)
		(in_bom no)
		(on_board yes)
		(dnp yes)
		(fields_autoplaced yes)
		(property "Reference" "R18"
			(at 208.28 205.74 0)
			(effects
				(font
					(size 1.27 1.27)
					(thickness 0.15)
				)
				(justify left bottom)
			)
		)
		(property "Value" "R_1M_0402"
			(at 229.87 220.98 0)
			(effects
				(font
					(size 1.27 1.27)
					(thickness 0.15)
				)
				(justify left bottom)
				(hide yes)
			)
		)
		(property "Footprint" "antmicro-footprints:R_0402_1005Metric"
			(at 229.87 223.52 0)
			(effects
				(font
					(size 1.27 1.27)
					(thickness 0.15)
				)
				(justify left bottom)
				(hide yes)
			)
		)
		(property "Datasheet" "https://www.bourns.com/docs/product-datasheets/cr.pdf"
			(at 229.87 226.06 0)
			(effects
				(font
					(size 1.27 1.27)
					(thickness 0.15)
				)
				(justify left bottom)
				(hide yes)
			)
		)
		(property "Description" "SMD Chip Resistor, 1 Mohm, ± 1%, 62.5 mW, 0402 [1005 Metric], Thick Film, General Purpose"
			(at 209.55 208.28 0)
			(effects
				(font
					(size 1.27 1.27)
				)
				(hide yes)
			)
		)
		(property "Manufacturer" "Bourns"
			(at 229.87 231.14 0)
			(effects
				(font
					(size 1.27 1.27)
					(thickness 0.15)
				)
				(justify left bottom)
				(hide yes)
			)
		)
		(property "MPN" "CR0402-FX-1004GLF"
			(at 229.87 228.6 0)
			(effects
				(font
					(size 1.27 1.27)
					(thickness 0.15)
				)
				(justify left bottom)
				(hide yes)
			)
		)
		(property "Val" "1M"
			(at 213.36 205.74 0)
			(effects
				(font
					(size 1.27 1.27)
					(thickness 0.15)
				)
				(justify left bottom)
			)
		)
		(property "License" "Apache-2.0"
			(at 229.87 233.68 0)
			(effects
				(font
					(size 1.27 1.27)
					(thickness 0.15)
				)
				(justify left bottom)
				(hide yes)
			)
		)
		(property "Author" "Antmicro"
			(at 229.87 236.22 0)
			(effects
				(font
					(size 1.27 1.27)
					(thickness 0.15)
				)
				(justify left bottom)
				(hide yes)
			)
		)
		(property "Tolerance" "1%"
			(at 229.87 218.44 0)
			(effects
				(font
					(size 1.27 1.27)
				)
				(justify left bottom)
				(hide yes)
			)
		)
		(property "Public" "False"
			(at 229.87 238.76 0)
			(effects
				(font
					(size 1.27 1.27)
				)
				(justify left bottom)
				(hide yes)
			)
		)
		(pin "1"
		)
		(pin "2"
		)
		(instances
			(project "environment-sensor"
				(path ""
					(reference "R18")
					(unit 1)
				)
			)
		)
	)
	(symbol
		(lib_id "antmicroResistors0402:R_0R_0402")
		(at 135.89 182.88 0)
		(unit 1)
		(exclude_from_sim no)
		(in_bom yes)
		(on_board yes)
		(dnp no)
		(fields_autoplaced yes)
		(property "Reference" "R14"
			(at 135.89 185.42 0)
			(effects
				(font
					(size 1.27 1.27)
					(thickness 0.15)
				)
			)
		)
		(property "Value" "R_0R_0402"
			(at 156.21 195.58 0)
			(effects
				(font
					(size 1.27 1.27)
					(thickness 0.15)
				)
				(justify left bottom)
				(hide yes)
			)
		)
		(property "Footprint" "antmicro-footprints:R_0402_1005Metric"
			(at 156.21 198.12 0)
			(effects
				(font
					(size 1.27 1.27)
					(thickness 0.15)
				)
				(justify left bottom)
				(hide yes)
			)
		)
		(property "Datasheet" "https://industrial.panasonic.com/cdbs/www-data/pdf/RDA0000/AOA0000C301.pdf"
			(at 156.21 200.66 0)
			(effects
				(font
					(size 1.27 1.27)
					(thickness 0.15)
				)
				(justify left bottom)
				(hide yes)
			)
		)
		(property "Description" "SMD Chip Resistor, Jumper, 0 ohm, 100 mW, 0402 [1005 Metric], Thick Film, General Purpose"
			(at 135.89 182.88 0)
			(effects
				(font
					(size 1.27 1.27)
				)
				(hide yes)
			)
		)
		(property "Manufacturer" "Panasonic"
			(at 156.21 205.74 0)
			(effects
				(font
					(size 1.27 1.27)
					(thickness 0.15)
				)
				(justify left bottom)
				(hide yes)
			)
		)
		(property "MPN" "ERJ2GE0R00X"
			(at 156.21 203.2 0)
			(effects
				(font
					(size 1.27 1.27)
					(thickness 0.15)
				)
				(justify left bottom)
				(hide yes)
			)
		)
		(property "Val" "0R"
			(at 139.7 185.42 0)
			(effects
				(font
					(size 1.27 1.27)
					(thickness 0.15)
				)
			)
		)
		(property "License" "Apache-2.0"
			(at 156.21 208.28 0)
			(effects
				(font
					(size 1.27 1.27)
					(thickness 0.15)
				)
				(justify left bottom)
				(hide yes)
			)
		)
		(property "Author" "Antmicro"
			(at 156.21 210.82 0)
			(effects
				(font
					(size 1.27 1.27)
					(thickness 0.15)
				)
				(justify left bottom)
				(hide yes)
			)
		)
		(property "Tolerance" "~"
			(at 156.21 193.04 0)
			(effects
				(font
					(size 1.27 1.27)
				)
				(justify left bottom)
				(hide yes)
			)
		)
		(property "Current" "1A"
			(at 138.43 182.88 0)
			(effects
				(font
					(size 1.27 1.27)
					(thickness 0.15)
				)
				(hide yes)
			)
		)
		(property "Public" "False"
			(at 156.21 213.36 0)
			(effects
				(font
					(size 1.27 1.27)
				)
				(justify left bottom)
				(hide yes)
			)
		)
		(pin "1"
		)
		(pin "2"
		)
		(instances
			(project "environment-sensor"
				(path ""
					(reference "R14")
					(unit 1)
				)
			)
		)
	)
	(symbol
		(lib_id "antmicropower:GND")
		(at 135.89 73.66 0)
		(unit 1)
		(exclude_from_sim no)
		(in_bom yes)
		(on_board yes)
		(dnp no)
		(fields_autoplaced yes)
		(property "Reference" "#PWR018"
			(at 135.89 80.01 0)
			(effects
				(font
					(size 1.27 1.27)
				)
				(hide yes)
			)
		)
		(property "Value" "GND"
			(at 135.89 78.74 0)
			(effects
				(font
					(size 1.27 1.27)
				)
			)
		)
		(property "Footprint" ""
			(at 135.89 73.66 0)
			(effects
				(font
					(size 1.27 1.27)
				)
				(hide yes)
			)
		)
		(property "Datasheet" ""
			(at 135.89 73.66 0)
			(effects
				(font
					(size 1.27 1.27)
				)
				(hide yes)
			)
		)
		(property "Description" ""
			(at 135.89 73.66 0)
			(effects
				(font
					(size 1.27 1.27)
				)
				(hide yes)
			)
		)
		(property "Author" "Antmicro"
			(at 144.78 81.28 0)
			(effects
				(font
					(size 1.27 1.27)
					(thickness 0.15)
				)
				(justify left bottom)
				(hide yes)
			)
		)
		(property "License" "Apache-2.0"
			(at 144.78 83.82 0)
			(effects
				(font
					(size 1.27 1.27)
					(thickness 0.15)
				)
				(justify left bottom)
				(hide yes)
			)
		)
		(pin "1"
		)
		(instances
			(project "environment-sensor"
				(path ""
					(reference "#PWR018")
					(unit 1)
				)
			)
		)
	)
	(symbol
		(lib_id "antmicroCapacitors0402:C_100n_0402")
		(at 45.72 185.42 90)
		(unit 1)
		(exclude_from_sim no)
		(in_bom yes)
		(on_board yes)
		(dnp no)
		(fields_autoplaced yes)
		(property "Reference" "C3"
			(at 48.26 181.6035 90)
			(effects
				(font
					(size 1.27 1.27)
					(thickness 0.15)
				)
				(justify right)
			)
		)
		(property "Value" "C_100n_0402"
			(at 55.88 165.1 0)
			(effects
				(font
					(size 1.27 1.27)
					(thickness 0.15)
				)
				(justify left bottom)
				(hide yes)
			)
		)
		(property "Footprint" "antmicro-footprints:C_0402_1005Metric"
			(at 58.42 165.1 0)
			(effects
				(font
					(size 1.27 1.27)
					(thickness 0.15)
				)
				(justify left bottom)
				(hide yes)
			)
		)
		(property "Datasheet" "https://www.murata.com/products/productdetail?partno=GRM155R61H104KE14%23"
			(at 60.96 165.1 0)
			(effects
				(font
					(size 1.27 1.27)
					(thickness 0.15)
				)
				(justify left bottom)
				(hide yes)
			)
		)
		(property "Description" "SMD Multilayer Ceramic Capacitor, 0.1 µF, 50 V, 0402 [1005 Metric], ± 10%, X5R, GRM Series"
			(at 45.72 185.42 0)
			(effects
				(font
					(size 1.27 1.27)
				)
				(hide yes)
			)
		)
		(property "Manufacturer" "Murata"
			(at 66.04 165.1 0)
			(effects
				(font
					(size 1.27 1.27)
					(thickness 0.15)
				)
				(justify left bottom)
				(hide yes)
			)
		)
		(property "MPN" "GRM155R61H104KE14D"
			(at 63.5 165.1 0)
			(effects
				(font
					(size 1.27 1.27)
					(thickness 0.15)
				)
				(justify left bottom)
				(hide yes)
			)
		)
		(property "Val" "100n"
			(at 48.26 184.1435 90)
			(effects
				(font
					(size 1.27 1.27)
					(thickness 0.15)
				)
				(justify right)
			)
		)
		(property "License" "Apache-2.0"
			(at 68.58 165.1 0)
			(effects
				(font
					(size 1.27 1.27)
					(thickness 0.15)
				)
				(justify left bottom)
				(hide yes)
			)
		)
		(property "Author" "Antmicro"
			(at 71.12 165.1 0)
			(effects
				(font
					(size 1.27 1.27)
					(thickness 0.15)
				)
				(justify left bottom)
				(hide yes)
			)
		)
		(property "Voltage" "50V"
			(at 73.66 165.1 0)
			(effects
				(font
					(size 1.27 1.27)
				)
				(justify left bottom)
				(hide yes)
			)
		)
		(property "Dielectric" "X5R"
			(at 76.2 165.1 0)
			(effects
				(font
					(size 1.27 1.27)
				)
				(justify left bottom)
				(hide yes)
			)
		)
		(property "Public" "False"
			(at 78.74 165.1 0)
			(effects
				(font
					(size 1.27 1.27)
				)
				(justify left bottom)
				(hide yes)
			)
		)
		(pin "1"
		)
		(pin "2"
		)
		(instances
			(project "environment-sensor"
				(path ""
					(reference "C3")
					(unit 1)
				)
			)
		)
	)
	(symbol
		(lib_id "antmicropower:GND")
		(at 210.82 179.07 0)
		(mirror y)
		(unit 1)
		(exclude_from_sim no)
		(in_bom yes)
		(on_board yes)
		(dnp no)
		(fields_autoplaced yes)
		(property "Reference" "#PWR028"
			(at 210.82 185.42 0)
			(effects
				(font
					(size 1.27 1.27)
				)
				(hide yes)
			)
		)
		(property "Value" "GND"
			(at 208.28 180.3399 0)
			(effects
				(font
					(size 1.27 1.27)
				)
				(justify left)
			)
		)
		(property "Footprint" ""
			(at 210.82 179.07 0)
			(effects
				(font
					(size 1.27 1.27)
				)
				(hide yes)
			)
		)
		(property "Datasheet" ""
			(at 210.82 179.07 0)
			(effects
				(font
					(size 1.27 1.27)
				)
				(hide yes)
			)
		)
		(property "Description" ""
			(at 210.82 179.07 0)
			(effects
				(font
					(size 1.27 1.27)
				)
				(hide yes)
			)
		)
		(property "Author" "Antmicro"
			(at 201.93 186.69 0)
			(effects
				(font
					(size 1.27 1.27)
					(thickness 0.15)
				)
				(justify left bottom)
				(hide yes)
			)
		)
		(property "License" "Apache-2.0"
			(at 201.93 189.23 0)
			(effects
				(font
					(size 1.27 1.27)
					(thickness 0.15)
				)
				(justify left bottom)
				(hide yes)
			)
		)
		(pin "1"
		)
		(instances
			(project "environment-sensor"
				(path ""
					(reference "#PWR028")
					(unit 1)
				)
			)
		)
	)
	(symbol
		(lib_id "antmicroTestPoints:TP_1mm_SMD")
		(at 391.16 55.88 0)
		(unit 1)
		(exclude_from_sim no)
		(in_bom yes)
		(on_board yes)
		(dnp no)
		(fields_autoplaced yes)
		(property "Reference" "TP12"
			(at 396.24 55.8799 0)
			(effects
				(font
					(size 1.27 1.27)
					(thickness 0.15)
				)
				(justify left)
			)
		)
		(property "Value" "TP_1mm_SMD"
			(at 396.24 57.1499 0)
			(effects
				(font
					(size 1.27 1.27)
					(thickness 0.15)
				)
				(justify left)
				(hide yes)
			)
		)
		(property "Footprint" "antmicro-footprints:TP_SMD_1mm"
			(at 406.4 66.04 0)
			(effects
				(font
					(size 1.27 1.27)
					(thickness 0.15)
				)
				(justify left bottom)
				(hide yes)
			)
		)
		(property "Datasheet" ""
			(at 406.4 68.58 0)
			(effects
				(font
					(size 1.27 1.27)
					(thickness 0.15)
				)
				(justify left bottom)
				(hide yes)
			)
		)
		(property "Description" "Test point 1mm SMD"
			(at 391.16 55.88 0)
			(effects
				(font
					(size 1.27 1.27)
				)
				(hide yes)
			)
		)
		(property "Author" "Antmicro"
			(at 406.4 71.12 0)
			(effects
				(font
					(size 1.27 1.27)
					(thickness 0.15)
				)
				(justify left bottom)
				(hide yes)
			)
		)
		(property "License" "Apache-2.0"
			(at 406.4 73.66 0)
			(effects
				(font
					(size 1.27 1.27)
					(thickness 0.15)
				)
				(justify left bottom)
				(hide yes)
			)
		)
		(property "MPN" ""
			(at 391.16 55.88 0)
			(effects
				(font
					(size 1.27 1.27)
				)
				(hide yes)
			)
		)
		(property "Manufacturer" ""
			(at 391.16 55.88 0)
			(effects
				(font
					(size 1.27 1.27)
				)
				(hide yes)
			)
		)
		(property "Public" "False"
			(at 406.4 76.2 0)
			(effects
				(font
					(size 1.27 1.27)
				)
				(justify left bottom)
				(hide yes)
			)
		)
		(pin "1"
		)
		(instances
			(project "environment-sensor"
				(path ""
					(reference "TP12")
					(unit 1)
				)
			)
		)
	)
	(symbol
		(lib_id "antmicroTVSDiodes:ESD9X5.0ST5G")
		(at 63.5 67.31 90)
		(unit 1)
		(exclude_from_sim no)
		(in_bom yes)
		(on_board yes)
		(dnp no)
		(fields_autoplaced yes)
		(property "Reference" "D2"
			(at 67.31 61.9124 90)
			(effects
				(font
					(size 1.27 1.27)
					(thickness 0.15)
				)
				(justify right)
			)
		)
		(property "Value" "ESD9X5.0ST5G"
			(at 67.31 64.4524 90)
			(effects
				(font
					(size 1.27 1.27)
					(thickness 0.15)
				)
				(justify right)
			)
		)
		(property "Footprint" "antmicro-footprints:SOD-923"
			(at 71.12 45.72 0)
			(effects
				(font
					(size 1.27 1.27)
					(thickness 0.15)
				)
				(justify left bottom)
				(hide yes)
			)
		)
		(property "Datasheet" "https://www.onsemi.com/pdf/datasheet/esd9x3.3st5g-d.pdf"
			(at 73.66 45.72 0)
			(effects
				(font
					(size 1.27 1.27)
					(thickness 0.15)
				)
				(justify left bottom)
				(hide yes)
			)
		)
		(property "Description" "Unidirectional TVS, 30 kV,  SOD-923, 5 V, 65 pF"
			(at 63.5 67.31 0)
			(effects
				(font
					(size 1.27 1.27)
				)
				(hide yes)
			)
		)
		(property "Manufacturer" "ON Semiconductor"
			(at 76.2 45.72 0)
			(effects
				(font
					(size 1.27 1.27)
					(thickness 0.15)
				)
				(justify left bottom)
				(hide yes)
			)
		)
		(property "MPN" "ESD9X5.0ST5G"
			(at 78.74 45.72 0)
			(effects
				(font
					(size 1.27 1.27)
					(thickness 0.15)
				)
				(justify left bottom)
				(hide yes)
			)
		)
		(property "Author" "Antmicro"
			(at 81.28 45.72 0)
			(effects
				(font
					(size 1.27 1.27)
					(thickness 0.15)
				)
				(justify left bottom)
				(hide yes)
			)
		)
		(property "License" "Apache-2.0"
			(at 83.82 45.72 0)
			(effects
				(font
					(size 1.27 1.27)
					(thickness 0.15)
				)
				(justify left bottom)
				(hide yes)
			)
		)
		(property "Public" "False"
			(at 81.28 46.99 0)
			(effects
				(font
					(size 1.27 1.27)
				)
				(justify left bottom)
				(hide yes)
			)
		)
		(pin "1"
		)
		(pin "2"
		)
		(instances
			(project "environment-sensor"
				(path ""
					(reference "D2")
					(unit 1)
				)
			)
		)
	)
	(symbol
		(lib_id "antmicroResistors0402:R_100R_0402")
		(at 288.29 161.29 0)
		(unit 1)
		(exclude_from_sim no)
		(in_bom yes)
		(on_board yes)
		(dnp no)
		(fields_autoplaced yes)
		(property "Reference" "R27"
			(at 290.83 156.21 0)
			(effects
				(font
					(size 1.27 1.27)
					(thickness 0.15)
				)
			)
		)
		(property "Value" "R_100R_0402"
			(at 308.61 173.99 0)
			(effects
				(font
					(size 1.27 1.27)
					(thickness 0.15)
				)
				(justify left bottom)
				(hide yes)
			)
		)
		(property "Footprint" "antmicro-footprints:R_0402_1005Metric"
			(at 308.61 176.53 0)
			(effects
				(font
					(size 1.27 1.27)
					(thickness 0.15)
				)
				(justify left bottom)
				(hide yes)
			)
		)
		(property "Datasheet" "https://www.bourns.com/docs/product-datasheets/cr.pdf"
			(at 308.61 179.07 0)
			(effects
				(font
					(size 1.27 1.27)
					(thickness 0.15)
				)
				(justify left bottom)
				(hide yes)
			)
		)
		(property "Description" "SMD Chip Resistor, 100 ohm, ± 1%, 62.5 mW, 0402 [1005 Metric], Thick Film, General Purpose"
			(at 288.29 161.29 0)
			(effects
				(font
					(size 1.27 1.27)
				)
				(hide yes)
			)
		)
		(property "Manufacturer" "Bourns"
			(at 308.61 184.15 0)
			(effects
				(font
					(size 1.27 1.27)
					(thickness 0.15)
				)
				(justify left bottom)
				(hide yes)
			)
		)
		(property "MPN" "CR0402-FX-1000GLF"
			(at 308.61 181.61 0)
			(effects
				(font
					(size 1.27 1.27)
					(thickness 0.15)
				)
				(justify left bottom)
				(hide yes)
			)
		)
		(property "Val" "100R"
			(at 290.83 158.75 0)
			(effects
				(font
					(size 1.27 1.27)
					(thickness 0.15)
				)
			)
		)
		(property "License" "Apache-2.0"
			(at 308.61 186.69 0)
			(effects
				(font
					(size 1.27 1.27)
					(thickness 0.15)
				)
				(justify left bottom)
				(hide yes)
			)
		)
		(property "Author" "Antmicro"
			(at 308.61 189.23 0)
			(effects
				(font
					(size 1.27 1.27)
					(thickness 0.15)
				)
				(justify left bottom)
				(hide yes)
			)
		)
		(property "Tolerance" "1%"
			(at 308.61 171.45 0)
			(effects
				(font
					(size 1.27 1.27)
				)
				(justify left bottom)
				(hide yes)
			)
		)
		(property "Public" "False"
			(at 308.61 191.77 0)
			(effects
				(font
					(size 1.27 1.27)
				)
				(justify left bottom)
				(hide yes)
			)
		)
		(pin "1"
		)
		(pin "2"
		)
		(instances
			(project "environment-sensor"
				(path ""
					(reference "R27")
					(unit 1)
				)
			)
		)
	)
	(symbol
		(lib_id "antmicropower:GND")
		(at 218.44 222.25 0)
		(unit 1)
		(exclude_from_sim no)
		(in_bom yes)
		(on_board yes)
		(dnp no)
		(fields_autoplaced yes)
		(property "Reference" "#PWR038"
			(at 218.44 228.6 0)
			(effects
				(font
					(size 1.27 1.27)
				)
				(hide yes)
			)
		)
		(property "Value" "GND"
			(at 218.44 227.33 0)
			(effects
				(font
					(size 1.27 1.27)
				)
			)
		)
		(property "Footprint" ""
			(at 218.44 222.25 0)
			(effects
				(font
					(size 1.27 1.27)
				)
				(hide yes)
			)
		)
		(property "Datasheet" ""
			(at 218.44 222.25 0)
			(effects
				(font
					(size 1.27 1.27)
				)
				(hide yes)
			)
		)
		(property "Description" ""
			(at 218.44 222.25 0)
			(effects
				(font
					(size 1.27 1.27)
				)
				(hide yes)
			)
		)
		(property "Author" "Antmicro"
			(at 227.33 229.87 0)
			(effects
				(font
					(size 1.27 1.27)
					(thickness 0.15)
				)
				(justify left bottom)
				(hide yes)
			)
		)
		(property "License" "Apache-2.0"
			(at 227.33 232.41 0)
			(effects
				(font
					(size 1.27 1.27)
					(thickness 0.15)
				)
				(justify left bottom)
				(hide yes)
			)
		)
		(pin "1"
		)
		(instances
			(project "environment-sensor"
				(path ""
					(reference "#PWR038")
					(unit 1)
				)
			)
		)
	)
	(symbol
		(lib_id "antmicroResistors0402:R_100R_0402")
		(at 237.49 186.69 180)
		(unit 1)
		(exclude_from_sim no)
		(in_bom no)
		(on_board yes)
		(dnp yes)
		(fields_autoplaced yes)
		(property "Reference" "R23"
			(at 231.14 189.23 0)
			(effects
				(font
					(size 1.27 1.27)
					(thickness 0.15)
				)
			)
		)
		(property "Value" "R_100R_0402"
			(at 217.17 173.99 0)
			(effects
				(font
					(size 1.27 1.27)
					(thickness 0.15)
				)
				(justify left bottom)
				(hide yes)
			)
		)
		(property "Footprint" "antmicro-footprints:R_0402_1005Metric"
			(at 217.17 171.45 0)
			(effects
				(font
					(size 1.27 1.27)
					(thickness 0.15)
				)
				(justify left bottom)
				(hide yes)
			)
		)
		(property "Datasheet" "https://www.bourns.com/docs/product-datasheets/cr.pdf"
			(at 217.17 168.91 0)
			(effects
				(font
					(size 1.27 1.27)
					(thickness 0.15)
				)
				(justify left bottom)
				(hide yes)
			)
		)
		(property "Description" "SMD Chip Resistor, 100 ohm, ± 1%, 62.5 mW, 0402 [1005 Metric], Thick Film, General Purpose"
			(at 237.49 186.69 0)
			(effects
				(font
					(size 1.27 1.27)
				)
				(hide yes)
			)
		)
		(property "Manufacturer" "Bourns"
			(at 217.17 163.83 0)
			(effects
				(font
					(size 1.27 1.27)
					(thickness 0.15)
				)
				(justify left bottom)
				(hide yes)
			)
		)
		(property "MPN" "CR0402-FX-1000GLF"
			(at 217.17 166.37 0)
			(effects
				(font
					(size 1.27 1.27)
					(thickness 0.15)
				)
				(justify left bottom)
				(hide yes)
			)
		)
		(property "Val" "100R"
			(at 236.22 189.23 0)
			(effects
				(font
					(size 1.27 1.27)
					(thickness 0.15)
				)
			)
		)
		(property "License" "Apache-2.0"
			(at 217.17 161.29 0)
			(effects
				(font
					(size 1.27 1.27)
					(thickness 0.15)
				)
				(justify left bottom)
				(hide yes)
			)
		)
		(property "Author" "Antmicro"
			(at 217.17 158.75 0)
			(effects
				(font
					(size 1.27 1.27)
					(thickness 0.15)
				)
				(justify left bottom)
				(hide yes)
			)
		)
		(property "Tolerance" "1%"
			(at 217.17 176.53 0)
			(effects
				(font
					(size 1.27 1.27)
				)
				(justify left bottom)
				(hide yes)
			)
		)
		(property "Public" "False"
			(at 217.17 156.21 0)
			(effects
				(font
					(size 1.27 1.27)
				)
				(justify left bottom)
				(hide yes)
			)
		)
		(pin "1"
		)
		(pin "2"
		)
		(instances
			(project "environment-sensor"
				(path ""
					(reference "R23")
					(unit 1)
				)
			)
		)
	)
	(symbol
		(lib_id "antmicropower:GND")
		(at 306.07 63.5 0)
		(mirror y)
		(unit 1)
		(exclude_from_sim no)
		(in_bom yes)
		(on_board yes)
		(dnp no)
		(fields_autoplaced yes)
		(property "Reference" "#PWR057"
			(at 306.07 69.85 0)
			(effects
				(font
					(size 1.27 1.27)
				)
				(hide yes)
			)
		)
		(property "Value" "GND"
			(at 306.07 68.58 0)
			(effects
				(font
					(size 1.27 1.27)
				)
			)
		)
		(property "Footprint" ""
			(at 306.07 63.5 0)
			(effects
				(font
					(size 1.27 1.27)
				)
				(hide yes)
			)
		)
		(property "Datasheet" ""
			(at 306.07 63.5 0)
			(effects
				(font
					(size 1.27 1.27)
				)
				(hide yes)
			)
		)
		(property "Description" ""
			(at 306.07 63.5 0)
			(effects
				(font
					(size 1.27 1.27)
				)
				(hide yes)
			)
		)
		(property "Author" "Antmicro"
			(at 297.18 71.12 0)
			(effects
				(font
					(size 1.27 1.27)
					(thickness 0.15)
				)
				(justify left bottom)
				(hide yes)
			)
		)
		(property "License" "Apache-2.0"
			(at 297.18 73.66 0)
			(effects
				(font
					(size 1.27 1.27)
					(thickness 0.15)
				)
				(justify left bottom)
				(hide yes)
			)
		)
		(pin "1"
		)
		(instances
			(project "environment-sensor"
				(path ""
					(reference "#PWR057")
					(unit 1)
				)
			)
		)
	)
	(symbol
		(lib_id "antmicroResistors0402:R_100k_0402")
		(at 306.07 60.96 270)
		(mirror x)
		(unit 1)
		(exclude_from_sim no)
		(in_bom yes)
		(on_board yes)
		(dnp no)
		(fields_autoplaced yes)
		(property "Reference" "R32"
			(at 308.61 57.1499 90)
			(effects
				(font
					(size 1.27 1.27)
					(thickness 0.15)
				)
				(justify left)
			)
		)
		(property "Value" "R_100k_0402"
			(at 293.37 40.64 0)
			(effects
				(font
					(size 1.27 1.27)
					(thickness 0.15)
				)
				(justify left bottom)
				(hide yes)
			)
		)
		(property "Footprint" "antmicro-footprints:R_0402_1005Metric"
			(at 290.83 40.64 0)
			(effects
				(font
					(size 1.27 1.27)
					(thickness 0.15)
				)
				(justify left bottom)
				(hide yes)
			)
		)
		(property "Datasheet" "https://www.bourns.com/docs/product-datasheets/cr.pdf"
			(at 288.29 40.64 0)
			(effects
				(font
					(size 1.27 1.27)
					(thickness 0.15)
				)
				(justify left bottom)
				(hide yes)
			)
		)
		(property "Description" "SMD Chip Resistor, 100 kohm, ± 1%, 62.5 mW, 0402 [1005 Metric], Thick Film, General Purpose"
			(at 306.07 60.96 0)
			(effects
				(font
					(size 1.27 1.27)
				)
				(hide yes)
			)
		)
		(property "Manufacturer" "Bourns"
			(at 283.21 40.64 0)
			(effects
				(font
					(size 1.27 1.27)
					(thickness 0.15)
				)
				(justify left bottom)
				(hide yes)
			)
		)
		(property "MPN" "CR0402-FX-1003GLF"
			(at 285.75 40.64 0)
			(effects
				(font
					(size 1.27 1.27)
					(thickness 0.15)
				)
				(justify left bottom)
				(hide yes)
			)
		)
		(property "Val" "100k"
			(at 308.61 59.6899 90)
			(effects
				(font
					(size 1.27 1.27)
					(thickness 0.15)
				)
				(justify left)
			)
		)
		(property "License" "Apache-2.0"
			(at 280.67 40.64 0)
			(effects
				(font
					(size 1.27 1.27)
					(thickness 0.15)
				)
				(justify left bottom)
				(hide yes)
			)
		)
		(property "Author" "Antmicro"
			(at 278.13 40.64 0)
			(effects
				(font
					(size 1.27 1.27)
					(thickness 0.15)
				)
				(justify left bottom)
				(hide yes)
			)
		)
		(property "Tolerance" "1%"
			(at 295.91 40.64 0)
			(effects
				(font
					(size 1.27 1.27)
				)
				(justify left bottom)
				(hide yes)
			)
		)
		(property "Public" "False"
			(at 275.59 40.64 0)
			(effects
				(font
					(size 1.27 1.27)
				)
				(justify left bottom)
				(hide yes)
			)
		)
		(pin "1"
		)
		(pin "2"
		)
		(instances
			(project "environment-sensor"
				(path ""
					(reference "R32")
					(unit 1)
				)
			)
		)
	)
	(symbol
		(lib_id "antmicroResistors0402:R_0R_0402")
		(at 101.6 198.12 0)
		(unit 1)
		(exclude_from_sim no)
		(in_bom yes)
		(on_board yes)
		(dnp no)
		(fields_autoplaced yes)
		(property "Reference" "R9"
			(at 100.965 196.85 0)
			(effects
				(font
					(size 1.27 1.27)
					(thickness 0.15)
				)
			)
		)
		(property "Value" "R_0R_0402"
			(at 121.92 210.82 0)
			(effects
				(font
					(size 1.27 1.27)
					(thickness 0.15)
				)
				(justify left bottom)
				(hide yes)
			)
		)
		(property "Footprint" "antmicro-footprints:R_0402_1005Metric"
			(at 121.92 213.36 0)
			(effects
				(font
					(size 1.27 1.27)
					(thickness 0.15)
				)
				(justify left bottom)
				(hide yes)
			)
		)
		(property "Datasheet" "https://industrial.panasonic.com/cdbs/www-data/pdf/RDA0000/AOA0000C301.pdf"
			(at 121.92 215.9 0)
			(effects
				(font
					(size 1.27 1.27)
					(thickness 0.15)
				)
				(justify left bottom)
				(hide yes)
			)
		)
		(property "Description" "SMD Chip Resistor, Jumper, 0 ohm, 100 mW, 0402 [1005 Metric], Thick Film, General Purpose"
			(at 101.6 198.12 0)
			(effects
				(font
					(size 1.27 1.27)
				)
				(hide yes)
			)
		)
		(property "Manufacturer" "Panasonic"
			(at 121.92 220.98 0)
			(effects
				(font
					(size 1.27 1.27)
					(thickness 0.15)
				)
				(justify left bottom)
				(hide yes)
			)
		)
		(property "MPN" "ERJ2GE0R00X"
			(at 121.92 218.44 0)
			(effects
				(font
					(size 1.27 1.27)
					(thickness 0.15)
				)
				(justify left bottom)
				(hide yes)
			)
		)
		(property "Val" "0R"
			(at 107.315 196.85 0)
			(effects
				(font
					(size 1.27 1.27)
					(thickness 0.15)
				)
			)
		)
		(property "License" "Apache-2.0"
			(at 121.92 223.52 0)
			(effects
				(font
					(size 1.27 1.27)
					(thickness 0.15)
				)
				(justify left bottom)
				(hide yes)
			)
		)
		(property "Author" "Antmicro"
			(at 121.92 226.06 0)
			(effects
				(font
					(size 1.27 1.27)
					(thickness 0.15)
				)
				(justify left bottom)
				(hide yes)
			)
		)
		(property "Tolerance" "~"
			(at 121.92 208.28 0)
			(effects
				(font
					(size 1.27 1.27)
				)
				(justify left bottom)
				(hide yes)
			)
		)
		(property "Current" "1A"
			(at 104.14 198.12 0)
			(effects
				(font
					(size 1.27 1.27)
					(thickness 0.15)
				)
				(hide yes)
			)
		)
		(property "Public" "False"
			(at 121.92 228.6 0)
			(effects
				(font
					(size 1.27 1.27)
				)
				(justify left bottom)
				(hide yes)
			)
		)
		(pin "1"
		)
		(pin "2"
		)
		(instances
			(project "environment-sensor"
				(path ""
					(reference "R9")
					(unit 1)
				)
			)
		)
	)
	(symbol
		(lib_id "antmicroResistors0402:R_100R_0402")
		(at 237.49 168.91 180)
		(unit 1)
		(exclude_from_sim no)
		(in_bom no)
		(on_board yes)
		(dnp yes)
		(fields_autoplaced yes)
		(property "Reference" "R22"
			(at 232.41 171.45 0)
			(effects
				(font
					(size 1.27 1.27)
					(thickness 0.15)
				)
			)
		)
		(property "Value" "R_100R_0402"
			(at 217.17 156.21 0)
			(effects
				(font
					(size 1.27 1.27)
					(thickness 0.15)
				)
				(justify left bottom)
				(hide yes)
			)
		)
		(property "Footprint" "antmicro-footprints:R_0402_1005Metric"
			(at 217.17 153.67 0)
			(effects
				(font
					(size 1.27 1.27)
					(thickness 0.15)
				)
				(justify left bottom)
				(hide yes)
			)
		)
		(property "Datasheet" "https://www.bourns.com/docs/product-datasheets/cr.pdf"
			(at 217.17 151.13 0)
			(effects
				(font
					(size 1.27 1.27)
					(thickness 0.15)
				)
				(justify left bottom)
				(hide yes)
			)
		)
		(property "Description" "SMD Chip Resistor, 100 ohm, ± 1%, 62.5 mW, 0402 [1005 Metric], Thick Film, General Purpose"
			(at 237.49 168.91 0)
			(effects
				(font
					(size 1.27 1.27)
				)
				(hide yes)
			)
		)
		(property "Manufacturer" "Bourns"
			(at 217.17 146.05 0)
			(effects
				(font
					(size 1.27 1.27)
					(thickness 0.15)
				)
				(justify left bottom)
				(hide yes)
			)
		)
		(property "MPN" "CR0402-FX-1000GLF"
			(at 217.17 148.59 0)
			(effects
				(font
					(size 1.27 1.27)
					(thickness 0.15)
				)
				(justify left bottom)
				(hide yes)
			)
		)
		(property "Val" "100R"
			(at 237.49 171.45 0)
			(effects
				(font
					(size 1.27 1.27)
					(thickness 0.15)
				)
			)
		)
		(property "License" "Apache-2.0"
			(at 217.17 143.51 0)
			(effects
				(font
					(size 1.27 1.27)
					(thickness 0.15)
				)
				(justify left bottom)
				(hide yes)
			)
		)
		(property "Author" "Antmicro"
			(at 217.17 140.97 0)
			(effects
				(font
					(size 1.27 1.27)
					(thickness 0.15)
				)
				(justify left bottom)
				(hide yes)
			)
		)
		(property "Tolerance" "1%"
			(at 217.17 158.75 0)
			(effects
				(font
					(size 1.27 1.27)
				)
				(justify left bottom)
				(hide yes)
			)
		)
		(property "Public" "False"
			(at 217.17 138.43 0)
			(effects
				(font
					(size 1.27 1.27)
				)
				(justify left bottom)
				(hide yes)
			)
		)
		(pin "1"
		)
		(pin "2"
		)
		(instances
			(project "environment-sensor"
				(path ""
					(reference "R22")
					(unit 1)
				)
			)
		)
	)
	(symbol
		(lib_id "antmicroResistors0402:R_0R_0402")
		(at 101.6 187.96 0)
		(unit 1)
		(exclude_from_sim no)
		(in_bom yes)
		(on_board yes)
		(dnp no)
		(fields_autoplaced yes)
		(property "Reference" "R6"
			(at 100.965 186.69 0)
			(effects
				(font
					(size 1.27 1.27)
					(thickness 0.15)
				)
			)
		)
		(property "Value" "R_0R_0402"
			(at 121.92 200.66 0)
			(effects
				(font
					(size 1.27 1.27)
					(thickness 0.15)
				)
				(justify left bottom)
				(hide yes)
			)
		)
		(property "Footprint" "antmicro-footprints:R_0402_1005Metric"
			(at 121.92 203.2 0)
			(effects
				(font
					(size 1.27 1.27)
					(thickness 0.15)
				)
				(justify left bottom)
				(hide yes)
			)
		)
		(property "Datasheet" "https://industrial.panasonic.com/cdbs/www-data/pdf/RDA0000/AOA0000C301.pdf"
			(at 121.92 205.74 0)
			(effects
				(font
					(size 1.27 1.27)
					(thickness 0.15)
				)
				(justify left bottom)
				(hide yes)
			)
		)
		(property "Description" "SMD Chip Resistor, Jumper, 0 ohm, 100 mW, 0402 [1005 Metric], Thick Film, General Purpose"
			(at 101.6 187.96 0)
			(effects
				(font
					(size 1.27 1.27)
				)
				(hide yes)
			)
		)
		(property "Manufacturer" "Panasonic"
			(at 121.92 210.82 0)
			(effects
				(font
					(size 1.27 1.27)
					(thickness 0.15)
				)
				(justify left bottom)
				(hide yes)
			)
		)
		(property "MPN" "ERJ2GE0R00X"
			(at 121.92 208.28 0)
			(effects
				(font
					(size 1.27 1.27)
					(thickness 0.15)
				)
				(justify left bottom)
				(hide yes)
			)
		)
		(property "Val" "0R"
			(at 107.315 186.69 0)
			(effects
				(font
					(size 1.27 1.27)
					(thickness 0.15)
				)
			)
		)
		(property "License" "Apache-2.0"
			(at 121.92 213.36 0)
			(effects
				(font
					(size 1.27 1.27)
					(thickness 0.15)
				)
				(justify left bottom)
				(hide yes)
			)
		)
		(property "Author" "Antmicro"
			(at 121.92 215.9 0)
			(effects
				(font
					(size 1.27 1.27)
					(thickness 0.15)
				)
				(justify left bottom)
				(hide yes)
			)
		)
		(property "Tolerance" "~"
			(at 121.92 198.12 0)
			(effects
				(font
					(size 1.27 1.27)
				)
				(justify left bottom)
				(hide yes)
			)
		)
		(property "Current" "1A"
			(at 104.14 187.96 0)
			(effects
				(font
					(size 1.27 1.27)
					(thickness 0.15)
				)
				(hide yes)
			)
		)
		(property "Public" "False"
			(at 121.92 218.44 0)
			(effects
				(font
					(size 1.27 1.27)
				)
				(justify left bottom)
				(hide yes)
			)
		)
		(pin "1"
		)
		(pin "2"
		)
		(instances
			(project "environment-sensor"
				(path ""
					(reference "R6")
					(unit 1)
				)
			)
		)
	)
	(symbol
		(lib_id "antmicroResistors0402:R_0R_0402")
		(at 101.6 203.2 0)
		(unit 1)
		(exclude_from_sim no)
		(in_bom no)
		(on_board yes)
		(dnp yes)
		(fields_autoplaced yes)
		(property "Reference" "R11"
			(at 100.33 201.93 0)
			(effects
				(font
					(size 1.27 1.27)
					(thickness 0.15)
				)
			)
		)
		(property "Value" "R_0R_0402"
			(at 121.92 215.9 0)
			(effects
				(font
					(size 1.27 1.27)
					(thickness 0.15)
				)
				(justify left bottom)
				(hide yes)
			)
		)
		(property "Footprint" "antmicro-footprints:R_0402_1005Metric"
			(at 121.92 218.44 0)
			(effects
				(font
					(size 1.27 1.27)
					(thickness 0.15)
				)
				(justify left bottom)
				(hide yes)
			)
		)
		(property "Datasheet" "https://industrial.panasonic.com/cdbs/www-data/pdf/RDA0000/AOA0000C301.pdf"
			(at 121.92 220.98 0)
			(effects
				(font
					(size 1.27 1.27)
					(thickness 0.15)
				)
				(justify left bottom)
				(hide yes)
			)
		)
		(property "Description" "SMD Chip Resistor, Jumper, 0 ohm, 100 mW, 0402 [1005 Metric], Thick Film, General Purpose"
			(at 101.6 203.2 0)
			(effects
				(font
					(size 1.27 1.27)
				)
				(hide yes)
			)
		)
		(property "Manufacturer" "Panasonic"
			(at 121.92 226.06 0)
			(effects
				(font
					(size 1.27 1.27)
					(thickness 0.15)
				)
				(justify left bottom)
				(hide yes)
			)
		)
		(property "MPN" "ERJ2GE0R00X"
			(at 121.92 223.52 0)
			(effects
				(font
					(size 1.27 1.27)
					(thickness 0.15)
				)
				(justify left bottom)
				(hide yes)
			)
		)
		(property "Val" "0R"
			(at 107.315 201.93 0)
			(effects
				(font
					(size 1.27 1.27)
					(thickness 0.15)
				)
			)
		)
		(property "License" "Apache-2.0"
			(at 121.92 228.6 0)
			(effects
				(font
					(size 1.27 1.27)
					(thickness 0.15)
				)
				(justify left bottom)
				(hide yes)
			)
		)
		(property "Author" "Antmicro"
			(at 121.92 231.14 0)
			(effects
				(font
					(size 1.27 1.27)
					(thickness 0.15)
				)
				(justify left bottom)
				(hide yes)
			)
		)
		(property "Tolerance" "~"
			(at 121.92 213.36 0)
			(effects
				(font
					(size 1.27 1.27)
				)
				(justify left bottom)
				(hide yes)
			)
		)
		(property "Current" "1A"
			(at 104.14 203.2 0)
			(effects
				(font
					(size 1.27 1.27)
					(thickness 0.15)
				)
				(hide yes)
			)
		)
		(property "Public" "False"
			(at 121.92 233.68 0)
			(effects
				(font
					(size 1.27 1.27)
				)
				(justify left bottom)
				(hide yes)
			)
		)
		(pin "1"
		)
		(pin "2"
		)
		(instances
			(project "environment-sensor"
				(path ""
					(reference "R11")
					(unit 1)
				)
			)
		)
	)
	(symbol
		(lib_id "antmicroResistors0402:R_1k_0402")
		(at 293.37 66.04 90)
		(unit 1)
		(exclude_from_sim no)
		(in_bom yes)
		(on_board yes)
		(dnp no)
		(fields_autoplaced yes)
		(property "Reference" "R26"
			(at 295.91 62.2299 90)
			(effects
				(font
					(size 1.27 1.27)
					(thickness 0.15)
				)
				(justify right)
			)
		)
		(property "Value" "R_1k_0402"
			(at 306.07 45.72 0)
			(effects
				(font
					(size 1.27 1.27)
					(thickness 0.15)
				)
				(justify left bottom)
				(hide yes)
			)
		)
		(property "Footprint" "antmicro-footprints:R_0402_1005Metric"
			(at 308.61 45.72 0)
			(effects
				(font
					(size 1.27 1.27)
					(thickness 0.15)
				)
				(justify left bottom)
				(hide yes)
			)
		)
		(property "Datasheet" "https://www.bourns.com/docs/product-datasheets/cr.pdf"
			(at 311.15 45.72 0)
			(effects
				(font
					(size 1.27 1.27)
					(thickness 0.15)
				)
				(justify left bottom)
				(hide yes)
			)
		)
		(property "Description" "SMD Chip Resistor, 1 kohm, ± 1%, 63 mW, 0402 [1005 Metric], Thick Film, General Purpose"
			(at 293.37 66.04 0)
			(effects
				(font
					(size 1.27 1.27)
				)
				(hide yes)
			)
		)
		(property "Manufacturer" "Bourns"
			(at 316.23 45.72 0)
			(effects
				(font
					(size 1.27 1.27)
					(thickness 0.15)
				)
				(justify left bottom)
				(hide yes)
			)
		)
		(property "MPN" "CR0402-FX-1001GLF"
			(at 313.69 45.72 0)
			(effects
				(font
					(size 1.27 1.27)
					(thickness 0.15)
				)
				(justify left bottom)
				(hide yes)
			)
		)
		(property "Val" "1k"
			(at 295.91 64.7699 90)
			(effects
				(font
					(size 1.27 1.27)
					(thickness 0.15)
				)
				(justify right)
			)
		)
		(property "License" "Apache-2.0"
			(at 318.77 45.72 0)
			(effects
				(font
					(size 1.27 1.27)
					(thickness 0.15)
				)
				(justify left bottom)
				(hide yes)
			)
		)
		(property "Author" "Antmicro"
			(at 321.31 45.72 0)
			(effects
				(font
					(size 1.27 1.27)
					(thickness 0.15)
				)
				(justify left bottom)
				(hide yes)
			)
		)
		(property "Tolerance" "1%"
			(at 303.53 45.72 0)
			(effects
				(font
					(size 1.27 1.27)
				)
				(justify left bottom)
				(hide yes)
			)
		)
		(property "Public" "False"
			(at 323.85 45.72 0)
			(effects
				(font
					(size 1.27 1.27)
				)
				(justify left bottom)
				(hide yes)
			)
		)
		(pin "1"
		)
		(pin "2"
		)
		(instances
			(project "environment-sensor"
				(path ""
					(reference "R26")
					(unit 1)
				)
			)
		)
	)
	(symbol
		(lib_id "antmicropower:+3V3")
		(at 215.9 262.89 0)
		(mirror y)
		(unit 1)
		(exclude_from_sim no)
		(in_bom yes)
		(on_board yes)
		(dnp no)
		(fields_autoplaced yes)
		(property "Reference" "#PWR030"
			(at 215.9 266.7 0)
			(effects
				(font
					(size 1.27 1.27)
				)
				(hide yes)
			)
		)
		(property "Value" "+3V3"
			(at 215.9 257.81 0)
			(effects
				(font
					(size 1.27 1.27)
				)
			)
		)
		(property "Footprint" ""
			(at 215.9 262.89 0)
			(effects
				(font
					(size 1.27 1.27)
				)
				(hide yes)
			)
		)
		(property "Datasheet" ""
			(at 215.9 262.89 0)
			(effects
				(font
					(size 1.27 1.27)
				)
				(hide yes)
			)
		)
		(property "Description" ""
			(at 215.9 262.89 0)
			(effects
				(font
					(size 1.27 1.27)
				)
				(hide yes)
			)
		)
		(property "Author" "Antmicro"
			(at 200.66 265.43 0)
			(effects
				(font
					(size 1.27 1.27)
					(thickness 0.15)
				)
				(justify left bottom)
				(hide yes)
			)
		)
		(property "License" "Apache-2.0"
			(at 200.66 267.97 0)
			(effects
				(font
					(size 1.27 1.27)
					(thickness 0.15)
				)
				(justify left bottom)
				(hide yes)
			)
		)
		(pin "1"
		)
		(instances
			(project "environment-sensor"
				(path ""
					(reference "#PWR030")
					(unit 1)
				)
			)
		)
	)
	(symbol
		(lib_id "antmicroMechanicalParts:MP_Pad5.4mm_Drill2.7mm")
		(at 269.24 261.62 90)
		(unit 1)
		(exclude_from_sim no)
		(in_bom no)
		(on_board yes)
		(dnp no)
		(fields_autoplaced yes)
		(property "Reference" "MP1"
			(at 273.05 255.27 90)
			(effects
				(font
					(size 1.27 1.27)
					(thickness 0.15)
				)
				(justify right)
			)
		)
		(property "Value" "MP_Pad5.4mm_Drill2.7mm"
			(at 273.05 257.81 90)
			(effects
				(font
					(size 1.27 1.27)
					(thickness 0.15)
				)
				(justify right)
			)
		)
		(property "Footprint" "antmicro-footprints:MP_Pad5.4mm_Drill2.7mm"
			(at 276.86 241.3 0)
			(effects
				(font
					(size 1.27 1.27)
					(thickness 0.15)
				)
				(justify left bottom)
				(hide yes)
			)
		)
		(property "Datasheet" ""
			(at 284.81 244.78 0)
			(effects
				(font
					(size 1.27 1.27)
					(thickness 0.15)
				)
				(justify left bottom)
				(hide yes)
			)
		)
		(property "Description" "Mechanical part"
			(at 269.24 261.62 0)
			(effects
				(font
					(size 1.27 1.27)
				)
				(hide yes)
			)
		)
		(property "Author" "Antmicro"
			(at 279.4 241.3 0)
			(effects
				(font
					(size 1.27 1.27)
					(thickness 0.15)
				)
				(justify left bottom)
				(hide yes)
			)
		)
		(property "License" "Apache-2.0"
			(at 281.94 241.3 0)
			(effects
				(font
					(size 1.27 1.27)
					(thickness 0.15)
				)
				(justify left bottom)
				(hide yes)
			)
		)
		(property "Public" "False"
			(at 284.48 241.3 0)
			(effects
				(font
					(size 1.27 1.27)
				)
				(justify left bottom)
				(hide yes)
			)
		)
		(pin "1"
		)
		(instances
			(project "environment-sensor"
				(path ""
					(reference "MP1")
					(unit 1)
				)
			)
		)
	)
	(symbol
		(lib_id "antmicroCapacitors0402:C_2u2_0402")
		(at 289.56 111.76 90)
		(mirror x)
		(unit 1)
		(exclude_from_sim no)
		(in_bom yes)
		(on_board yes)
		(dnp no)
		(fields_autoplaced yes)
		(property "Reference" "C11"
			(at 287.02 113.0362 90)
			(effects
				(font
					(size 1.27 1.27)
					(thickness 0.15)
				)
				(justify left)
			)
		)
		(property "Value" "C_2u2_0402"
			(at 299.72 132.08 0)
			(effects
				(font
					(size 1.27 1.27)
					(thickness 0.15)
				)
				(justify left bottom)
				(hide yes)
			)
		)
		(property "Footprint" "antmicro-footprints:C_0402_1005Metric"
			(at 302.26 132.08 0)
			(effects
				(font
					(size 1.27 1.27)
					(thickness 0.15)
				)
				(justify left bottom)
				(hide yes)
			)
		)
		(property "Datasheet" "https://product.tdk.com/en/search/capacitor/ceramic/mlcc/info?part_no=C1005X5R1A225K050BC"
			(at 304.8 132.08 0)
			(effects
				(font
					(size 1.27 1.27)
					(thickness 0.15)
				)
				(justify left bottom)
				(hide yes)
			)
		)
		(property "Description" "SMD Multilayer Ceramic Capacitor, 2.2 µF, 10 V, 0402 [1005 Metric], ± 10%, X5R, C"
			(at 289.56 111.76 0)
			(effects
				(font
					(size 1.27 1.27)
				)
				(hide yes)
			)
		)
		(property "Manufacturer" "TDK"
			(at 309.88 132.08 0)
			(effects
				(font
					(size 1.27 1.27)
					(thickness 0.15)
				)
				(justify left bottom)
				(hide yes)
			)
		)
		(property "MPN" "C1005X5R1A225K050BC"
			(at 307.34 132.08 0)
			(effects
				(font
					(size 1.27 1.27)
					(thickness 0.15)
				)
				(justify left bottom)
				(hide yes)
			)
		)
		(property "Val" "2u2"
			(at 287.02 115.5762 90)
			(effects
				(font
					(size 1.27 1.27)
					(thickness 0.15)
				)
				(justify left)
			)
		)
		(property "License" "Apache-2.0"
			(at 312.42 132.08 0)
			(effects
				(font
					(size 1.27 1.27)
					(thickness 0.15)
				)
				(justify left bottom)
				(hide yes)
			)
		)
		(property "Author" "Antmicro"
			(at 314.96 132.08 0)
			(effects
				(font
					(size 1.27 1.27)
					(thickness 0.15)
				)
				(justify left bottom)
				(hide yes)
			)
		)
		(property "Voltage" ""
			(at 317.5 132.08 0)
			(effects
				(font
					(size 1.27 1.27)
				)
				(justify left bottom)
				(hide yes)
			)
		)
		(property "Dielectric" ""
			(at 320.04 132.08 0)
			(effects
				(font
					(size 1.27 1.27)
				)
				(justify left bottom)
				(hide yes)
			)
		)
		(property "Public" "False"
			(at 322.58 132.08 0)
			(effects
				(font
					(size 1.27 1.27)
				)
				(justify left bottom)
				(hide yes)
			)
		)
		(pin "1"
		)
		(pin "2"
		)
		(instances
			(project "environment-sensor"
				(path ""
					(reference "C11")
					(unit 1)
				)
			)
		)
	)
	(symbol
		(lib_id "antmicropower:GND")
		(at 195.58 264.16 0)
		(mirror y)
		(unit 1)
		(exclude_from_sim no)
		(in_bom yes)
		(on_board yes)
		(dnp no)
		(fields_autoplaced yes)
		(property "Reference" "#PWR024"
			(at 195.58 270.51 0)
			(effects
				(font
					(size 1.27 1.27)
				)
				(hide yes)
			)
		)
		(property "Value" "GND"
			(at 195.58 269.24 0)
			(effects
				(font
					(size 1.27 1.27)
				)
			)
		)
		(property "Footprint" ""
			(at 195.58 264.16 0)
			(effects
				(font
					(size 1.27 1.27)
				)
				(hide yes)
			)
		)
		(property "Datasheet" ""
			(at 195.58 264.16 0)
			(effects
				(font
					(size 1.27 1.27)
				)
				(hide yes)
			)
		)
		(property "Description" ""
			(at 195.58 264.16 0)
			(effects
				(font
					(size 1.27 1.27)
				)
				(hide yes)
			)
		)
		(property "Author" "Antmicro"
			(at 186.69 271.78 0)
			(effects
				(font
					(size 1.27 1.27)
					(thickness 0.15)
				)
				(justify left bottom)
				(hide yes)
			)
		)
		(property "License" "Apache-2.0"
			(at 186.69 274.32 0)
			(effects
				(font
					(size 1.27 1.27)
					(thickness 0.15)
				)
				(justify left bottom)
				(hide yes)
			)
		)
		(pin "1"
		)
		(instances
			(project "environment-sensor"
				(path ""
					(reference "#PWR024")
					(unit 1)
				)
			)
		)
	)
	(symbol
		(lib_id "antmicropower:GND")
		(at 93.98 115.57 0)
		(mirror y)
		(unit 1)
		(exclude_from_sim no)
		(in_bom yes)
		(on_board yes)
		(dnp no)
		(fields_autoplaced yes)
		(property "Reference" "#PWR013"
			(at 93.98 121.92 0)
			(effects
				(font
					(size 1.27 1.27)
				)
				(hide yes)
			)
		)
		(property "Value" "GND"
			(at 93.98 120.65 0)
			(effects
				(font
					(size 1.27 1.27)
				)
			)
		)
		(property "Footprint" ""
			(at 93.98 115.57 0)
			(effects
				(font
					(size 1.27 1.27)
				)
				(hide yes)
			)
		)
		(property "Datasheet" ""
			(at 93.98 115.57 0)
			(effects
				(font
					(size 1.27 1.27)
				)
				(hide yes)
			)
		)
		(property "Description" ""
			(at 93.98 115.57 0)
			(effects
				(font
					(size 1.27 1.27)
				)
				(hide yes)
			)
		)
		(property "Author" "Antmicro"
			(at 85.09 123.19 0)
			(effects
				(font
					(size 1.27 1.27)
					(thickness 0.15)
				)
				(justify left bottom)
				(hide yes)
			)
		)
		(property "License" "Apache-2.0"
			(at 85.09 125.73 0)
			(effects
				(font
					(size 1.27 1.27)
					(thickness 0.15)
				)
				(justify left bottom)
				(hide yes)
			)
		)
		(pin "1"
		)
		(instances
			(project "environment-sensor"
				(path ""
					(reference "#PWR013")
					(unit 1)
				)
			)
		)
	)
	(symbol
		(lib_id "antmicropower:GND")
		(at 87.63 73.66 0)
		(unit 1)
		(exclude_from_sim no)
		(in_bom yes)
		(on_board yes)
		(dnp no)
		(fields_autoplaced yes)
		(property "Reference" "#PWR012"
			(at 87.63 80.01 0)
			(effects
				(font
					(size 1.27 1.27)
				)
				(hide yes)
			)
		)
		(property "Value" "GND"
			(at 85.09 74.9299 0)
			(effects
				(font
					(size 1.27 1.27)
				)
				(justify right)
			)
		)
		(property "Footprint" ""
			(at 87.63 73.66 0)
			(effects
				(font
					(size 1.27 1.27)
				)
				(hide yes)
			)
		)
		(property "Datasheet" ""
			(at 87.63 73.66 0)
			(effects
				(font
					(size 1.27 1.27)
				)
				(hide yes)
			)
		)
		(property "Description" ""
			(at 87.63 73.66 0)
			(effects
				(font
					(size 1.27 1.27)
				)
				(hide yes)
			)
		)
		(property "Author" "Antmicro"
			(at 96.52 81.28 0)
			(effects
				(font
					(size 1.27 1.27)
					(thickness 0.15)
				)
				(justify left bottom)
				(hide yes)
			)
		)
		(property "License" "Apache-2.0"
			(at 96.52 83.82 0)
			(effects
				(font
					(size 1.27 1.27)
					(thickness 0.15)
				)
				(justify left bottom)
				(hide yes)
			)
		)
		(pin "1"
		)
		(instances
			(project "environment-sensor"
				(path ""
					(reference "#PWR012")
					(unit 1)
				)
			)
		)
	)
	(symbol
		(lib_id "antmicropower:GND")
		(at 215.9 273.05 0)
		(mirror y)
		(unit 1)
		(exclude_from_sim no)
		(in_bom yes)
		(on_board yes)
		(dnp no)
		(fields_autoplaced yes)
		(property "Reference" "#PWR031"
			(at 215.9 279.4 0)
			(effects
				(font
					(size 1.27 1.27)
				)
				(hide yes)
			)
		)
		(property "Value" "GND"
			(at 215.9 278.13 0)
			(effects
				(font
					(size 1.27 1.27)
				)
			)
		)
		(property "Footprint" ""
			(at 215.9 273.05 0)
			(effects
				(font
					(size 1.27 1.27)
				)
				(hide yes)
			)
		)
		(property "Datasheet" ""
			(at 215.9 273.05 0)
			(effects
				(font
					(size 1.27 1.27)
				)
				(hide yes)
			)
		)
		(property "Description" ""
			(at 215.9 273.05 0)
			(effects
				(font
					(size 1.27 1.27)
				)
				(hide yes)
			)
		)
		(property "Author" "Antmicro"
			(at 207.01 280.67 0)
			(effects
				(font
					(size 1.27 1.27)
					(thickness 0.15)
				)
				(justify left bottom)
				(hide yes)
			)
		)
		(property "License" "Apache-2.0"
			(at 207.01 283.21 0)
			(effects
				(font
					(size 1.27 1.27)
					(thickness 0.15)
				)
				(justify left bottom)
				(hide yes)
			)
		)
		(pin "1"
		)
		(instances
			(project "environment-sensor"
				(path ""
					(reference "#PWR031")
					(unit 1)
				)
			)
		)
	)
	(symbol
		(lib_id "antmicropower:GND")
		(at 59.69 76.2 0)
		(unit 1)
		(exclude_from_sim no)
		(in_bom yes)
		(on_board yes)
		(dnp no)
		(fields_autoplaced yes)
		(property "Reference" "#PWR07"
			(at 59.69 82.55 0)
			(effects
				(font
					(size 1.27 1.27)
				)
				(hide yes)
			)
		)
		(property "Value" "GND"
			(at 60.96 81.28 0)
			(effects
				(font
					(size 1.27 1.27)
				)
				(justify right)
			)
		)
		(property "Footprint" ""
			(at 59.69 76.2 0)
			(effects
				(font
					(size 1.27 1.27)
				)
				(hide yes)
			)
		)
		(property "Datasheet" ""
			(at 59.69 76.2 0)
			(effects
				(font
					(size 1.27 1.27)
				)
				(hide yes)
			)
		)
		(property "Description" ""
			(at 59.69 76.2 0)
			(effects
				(font
					(size 1.27 1.27)
				)
				(hide yes)
			)
		)
		(property "Author" "Antmicro"
			(at 68.58 83.82 0)
			(effects
				(font
					(size 1.27 1.27)
					(thickness 0.15)
				)
				(justify left bottom)
				(hide yes)
			)
		)
		(property "License" "Apache-2.0"
			(at 68.58 86.36 0)
			(effects
				(font
					(size 1.27 1.27)
					(thickness 0.15)
				)
				(justify left bottom)
				(hide yes)
			)
		)
		(pin "1"
		)
		(instances
			(project "environment-sensor"
				(path ""
					(reference "#PWR07")
					(unit 1)
				)
			)
		)
	)
	(symbol
		(lib_id "antmicroResistors0402:R_470R_0402")
		(at 210.82 179.07 270)
		(mirror x)
		(unit 1)
		(exclude_from_sim no)
		(in_bom yes)
		(on_board yes)
		(dnp no)
		(fields_autoplaced yes)
		(property "Reference" "R17"
			(at 213.36 175.2599 90)
			(effects
				(font
					(size 1.27 1.27)
					(thickness 0.15)
				)
				(justify left)
			)
		)
		(property "Value" "R_470R_0402"
			(at 198.12 158.75 0)
			(effects
				(font
					(size 1.27 1.27)
					(thickness 0.15)
				)
				(justify left bottom)
				(hide yes)
			)
		)
		(property "Footprint" "antmicro-footprints:R_0402_1005Metric"
			(at 195.58 158.75 0)
			(effects
				(font
					(size 1.27 1.27)
					(thickness 0.15)
				)
				(justify left bottom)
				(hide yes)
			)
		)
		(property "Datasheet" "https://www.bourns.com/docs/product-datasheets/cr.pdf"
			(at 193.04 158.75 0)
			(effects
				(font
					(size 1.27 1.27)
					(thickness 0.15)
				)
				(justify left bottom)
				(hide yes)
			)
		)
		(property "Description" "SMD Chip Resistor, 470 ohm, ± 1%, 62.5 mW, 0402 [1005 Metric], Thick Film, General Purpose"
			(at 210.82 179.07 0)
			(effects
				(font
					(size 1.27 1.27)
				)
				(hide yes)
			)
		)
		(property "Manufacturer" "Bourns"
			(at 187.96 158.75 0)
			(effects
				(font
					(size 1.27 1.27)
					(thickness 0.15)
				)
				(justify left bottom)
				(hide yes)
			)
		)
		(property "MPN" "CR0402-FX-4700GLF"
			(at 190.5 158.75 0)
			(effects
				(font
					(size 1.27 1.27)
					(thickness 0.15)
				)
				(justify left bottom)
				(hide yes)
			)
		)
		(property "Val" "470R"
			(at 213.36 177.165 90)
			(effects
				(font
					(size 1.27 1.27)
					(thickness 0.15)
				)
				(justify left)
			)
		)
		(property "License" "Apache-2.0"
			(at 185.42 158.75 0)
			(effects
				(font
					(size 1.27 1.27)
					(thickness 0.15)
				)
				(justify left bottom)
				(hide yes)
			)
		)
		(property "Author" "Antmicro"
			(at 182.88 158.75 0)
			(effects
				(font
					(size 1.27 1.27)
					(thickness 0.15)
				)
				(justify left bottom)
				(hide yes)
			)
		)
		(property "Tolerance" "1%"
			(at 200.66 158.75 0)
			(effects
				(font
					(size 1.27 1.27)
				)
				(justify left bottom)
				(hide yes)
			)
		)
		(property "Public" "False"
			(at 180.34 158.75 0)
			(effects
				(font
					(size 1.27 1.27)
				)
				(justify left bottom)
				(hide yes)
			)
		)
		(pin "1"
		)
		(pin "2"
		)
		(instances
			(project "environment-sensor"
				(path ""
					(reference "R17")
					(unit 1)
				)
			)
		)
	)
	(symbol
		(lib_id "antmicropower:GND")
		(at 205.74 222.25 0)
		(unit 1)
		(exclude_from_sim no)
		(in_bom yes)
		(on_board yes)
		(dnp no)
		(fields_autoplaced yes)
		(property "Reference" "#PWR032"
			(at 205.74 228.6 0)
			(effects
				(font
					(size 1.27 1.27)
				)
				(hide yes)
			)
		)
		(property "Value" "GND"
			(at 205.74 227.33 0)
			(effects
				(font
					(size 1.27 1.27)
				)
			)
		)
		(property "Footprint" ""
			(at 205.74 222.25 0)
			(effects
				(font
					(size 1.27 1.27)
				)
				(hide yes)
			)
		)
		(property "Datasheet" ""
			(at 205.74 222.25 0)
			(effects
				(font
					(size 1.27 1.27)
				)
				(hide yes)
			)
		)
		(property "Description" ""
			(at 205.74 222.25 0)
			(effects
				(font
					(size 1.27 1.27)
				)
				(hide yes)
			)
		)
		(property "Author" "Antmicro"
			(at 214.63 229.87 0)
			(effects
				(font
					(size 1.27 1.27)
					(thickness 0.15)
				)
				(justify left bottom)
				(hide yes)
			)
		)
		(property "License" "Apache-2.0"
			(at 214.63 232.41 0)
			(effects
				(font
					(size 1.27 1.27)
					(thickness 0.15)
				)
				(justify left bottom)
				(hide yes)
			)
		)
		(pin "1"
		)
		(instances
			(project "environment-sensor"
				(path ""
					(reference "#PWR032")
					(unit 1)
				)
			)
		)
	)
	(symbol
		(lib_id "antmicroLEDIndicationDiscrete:LED_G_0603_KP-1608ZGC")
		(at 210.82 161.29 90)
		(mirror x)
		(unit 1)
		(exclude_from_sim no)
		(in_bom yes)
		(on_board yes)
		(dnp no)
		(fields_autoplaced yes)
		(property "Reference" "LD2"
			(at 207.01 162.56 90)
			(effects
				(font
					(size 1.27 1.27)
					(thickness 0.15)
				)
				(justify left)
			)
		)
		(property "Value" "LED_G_0603_KP-1608ZGC"
			(at 199.39 161.29 90)
			(effects
				(font
					(size 1.27 1.27)
					(thickness 0.15)
				)
				(justify right)
				(hide yes)
			)
		)
		(property "Footprint" "antmicro-footprints:LED_0603_1608Metric_G"
			(at 220.98 184.15 0)
			(effects
				(font
					(size 1.27 1.27)
					(thickness 0.15)
				)
				(justify left bottom)
				(hide yes)
			)
		)
		(property "Datasheet" "https://www.kingbright.com/attachments/file/psearch/000/00/00/KP-1608ZGC(Ver.19B).pdf"
			(at 223.52 184.15 0)
			(effects
				(font
					(size 1.27 1.27)
					(thickness 0.15)
				)
				(justify left bottom)
				(hide yes)
			)
		)
		(property "Description" "LED, Green, SMD, 0603, 20 mA, 3.3 V, 525 nm"
			(at 210.82 161.29 0)
			(effects
				(font
					(size 1.27 1.27)
				)
				(hide yes)
			)
		)
		(property "MPN" "KP-1608ZGC"
			(at 226.06 184.15 0)
			(effects
				(font
					(size 1.27 1.27)
					(thickness 0.15)
				)
				(justify left bottom)
				(hide yes)
			)
		)
		(property "Manufacturer" "Kingbright"
			(at 228.6 184.15 0)
			(effects
				(font
					(size 1.27 1.27)
					(thickness 0.15)
				)
				(justify left bottom)
				(hide yes)
			)
		)
		(property "Author" "Antmicro"
			(at 231.14 184.15 0)
			(effects
				(font
					(size 1.27 1.27)
					(thickness 0.15)
				)
				(justify left bottom)
				(hide yes)
			)
		)
		(property "License" "Apache-2.0"
			(at 233.68 184.15 0)
			(effects
				(font
					(size 1.27 1.27)
					(thickness 0.15)
				)
				(justify left bottom)
				(hide yes)
			)
		)
		(property "Color" "Green"
			(at 207.01 165.0999 90)
			(effects
				(font
					(size 1.27 1.27)
				)
				(justify left)
			)
		)
		(property "Public" "False"
			(at 228.6 181.61 0)
			(effects
				(font
					(size 1.27 1.27)
				)
				(justify left bottom)
				(hide yes)
			)
		)
		(pin "1"
		)
		(pin "2"
		)
		(instances
			(project "environment-sensor"
				(path ""
					(reference "LD2")
					(unit 1)
				)
			)
		)
	)
	(symbol
		(lib_id "antmicroResistors0402:R_100k_0402")
		(at 306.07 45.72 270)
		(mirror x)
		(unit 1)
		(exclude_from_sim no)
		(in_bom no)
		(on_board yes)
		(dnp yes)
		(fields_autoplaced yes)
		(property "Reference" "R31"
			(at 308.61 41.9099 90)
			(effects
				(font
					(size 1.27 1.27)
					(thickness 0.15)
				)
				(justify left)
			)
		)
		(property "Value" "R_100k_0402"
			(at 293.37 25.4 0)
			(effects
				(font
					(size 1.27 1.27)
					(thickness 0.15)
				)
				(justify left bottom)
				(hide yes)
			)
		)
		(property "Footprint" "antmicro-footprints:R_0402_1005Metric"
			(at 290.83 25.4 0)
			(effects
				(font
					(size 1.27 1.27)
					(thickness 0.15)
				)
				(justify left bottom)
				(hide yes)
			)
		)
		(property "Datasheet" "https://www.bourns.com/docs/product-datasheets/cr.pdf"
			(at 288.29 25.4 0)
			(effects
				(font
					(size 1.27 1.27)
					(thickness 0.15)
				)
				(justify left bottom)
				(hide yes)
			)
		)
		(property "Description" "SMD Chip Resistor, 100 kohm, ± 1%, 62.5 mW, 0402 [1005 Metric], Thick Film, General Purpose"
			(at 306.07 45.72 0)
			(effects
				(font
					(size 1.27 1.27)
				)
				(hide yes)
			)
		)
		(property "Manufacturer" "Bourns"
			(at 283.21 25.4 0)
			(effects
				(font
					(size 1.27 1.27)
					(thickness 0.15)
				)
				(justify left bottom)
				(hide yes)
			)
		)
		(property "MPN" "CR0402-FX-1003GLF"
			(at 285.75 25.4 0)
			(effects
				(font
					(size 1.27 1.27)
					(thickness 0.15)
				)
				(justify left bottom)
				(hide yes)
			)
		)
		(property "Val" "100k"
			(at 308.61 44.4499 90)
			(effects
				(font
					(size 1.27 1.27)
					(thickness 0.15)
				)
				(justify left)
			)
		)
		(property "License" "Apache-2.0"
			(at 280.67 25.4 0)
			(effects
				(font
					(size 1.27 1.27)
					(thickness 0.15)
				)
				(justify left bottom)
				(hide yes)
			)
		)
		(property "Author" "Antmicro"
			(at 278.13 25.4 0)
			(effects
				(font
					(size 1.27 1.27)
					(thickness 0.15)
				)
				(justify left bottom)
				(hide yes)
			)
		)
		(property "Tolerance" "1%"
			(at 295.91 25.4 0)
			(effects
				(font
					(size 1.27 1.27)
				)
				(justify left bottom)
				(hide yes)
			)
		)
		(property "Public" "False"
			(at 275.59 25.4 0)
			(effects
				(font
					(size 1.27 1.27)
				)
				(justify left bottom)
				(hide yes)
			)
		)
		(pin "1"
		)
		(pin "2"
		)
		(instances
			(project "environment-sensor"
				(path ""
					(reference "R31")
					(unit 1)
				)
			)
		)
	)
	(symbol
		(lib_id "antmicropower:GND")
		(at 99.06 115.57 0)
		(mirror y)
		(unit 1)
		(exclude_from_sim no)
		(in_bom yes)
		(on_board yes)
		(dnp no)
		(fields_autoplaced yes)
		(property "Reference" "#PWR015"
			(at 99.06 121.92 0)
			(effects
				(font
					(size 1.27 1.27)
				)
				(hide yes)
			)
		)
		(property "Value" "GND"
			(at 99.06 120.65 0)
			(effects
				(font
					(size 1.27 1.27)
				)
			)
		)
		(property "Footprint" ""
			(at 99.06 115.57 0)
			(effects
				(font
					(size 1.27 1.27)
				)
				(hide yes)
			)
		)
		(property "Datasheet" ""
			(at 99.06 115.57 0)
			(effects
				(font
					(size 1.27 1.27)
				)
				(hide yes)
			)
		)
		(property "Description" ""
			(at 99.06 115.57 0)
			(effects
				(font
					(size 1.27 1.27)
				)
				(hide yes)
			)
		)
		(property "Author" "Antmicro"
			(at 90.17 123.19 0)
			(effects
				(font
					(size 1.27 1.27)
					(thickness 0.15)
				)
				(justify left bottom)
				(hide yes)
			)
		)
		(property "License" "Apache-2.0"
			(at 90.17 125.73 0)
			(effects
				(font
					(size 1.27 1.27)
					(thickness 0.15)
				)
				(justify left bottom)
				(hide yes)
			)
		)
		(pin "1"
		)
		(instances
			(project "environment-sensor"
				(path ""
					(reference "#PWR015")
					(unit 1)
				)
			)
		)
	)
	(symbol
		(lib_id "antmicroResistors0402:R_100k_0402")
		(at 289.56 144.78 90)
		(unit 1)
		(exclude_from_sim no)
		(in_bom yes)
		(on_board yes)
		(dnp no)
		(fields_autoplaced yes)
		(property "Reference" "R24"
			(at 290.83 140.97 90)
			(effects
				(font
					(size 1.27 1.27)
					(thickness 0.15)
				)
				(justify right)
			)
		)
		(property "Value" "R_100k_0402"
			(at 302.26 124.46 0)
			(effects
				(font
					(size 1.27 1.27)
					(thickness 0.15)
				)
				(justify left bottom)
				(hide yes)
			)
		)
		(property "Footprint" "antmicro-footprints:R_0402_1005Metric"
			(at 304.8 124.46 0)
			(effects
				(font
					(size 1.27 1.27)
					(thickness 0.15)
				)
				(justify left bottom)
				(hide yes)
			)
		)
		(property "Datasheet" "https://www.bourns.com/docs/product-datasheets/cr.pdf"
			(at 307.34 124.46 0)
			(effects
				(font
					(size 1.27 1.27)
					(thickness 0.15)
				)
				(justify left bottom)
				(hide yes)
			)
		)
		(property "Description" "SMD Chip Resistor, 100 kohm, ± 1%, 62.5 mW, 0402 [1005 Metric], Thick Film, General Purpose"
			(at 289.56 144.78 0)
			(effects
				(font
					(size 1.27 1.27)
				)
				(hide yes)
			)
		)
		(property "Manufacturer" "Bourns"
			(at 312.42 124.46 0)
			(effects
				(font
					(size 1.27 1.27)
					(thickness 0.15)
				)
				(justify left bottom)
				(hide yes)
			)
		)
		(property "MPN" "CR0402-FX-1003GLF"
			(at 309.88 124.46 0)
			(effects
				(font
					(size 1.27 1.27)
					(thickness 0.15)
				)
				(justify left bottom)
				(hide yes)
			)
		)
		(property "Val" "100k"
			(at 290.83 143.51 90)
			(effects
				(font
					(size 1.27 1.27)
					(thickness 0.15)
				)
				(justify right)
			)
		)
		(property "License" "Apache-2.0"
			(at 314.96 124.46 0)
			(effects
				(font
					(size 1.27 1.27)
					(thickness 0.15)
				)
				(justify left bottom)
				(hide yes)
			)
		)
		(property "Author" "Antmicro"
			(at 317.5 124.46 0)
			(effects
				(font
					(size 1.27 1.27)
					(thickness 0.15)
				)
				(justify left bottom)
				(hide yes)
			)
		)
		(property "Tolerance" "1%"
			(at 299.72 124.46 0)
			(effects
				(font
					(size 1.27 1.27)
				)
				(justify left bottom)
				(hide yes)
			)
		)
		(property "Public" "False"
			(at 320.04 124.46 0)
			(effects
				(font
					(size 1.27 1.27)
				)
				(justify left bottom)
				(hide yes)
			)
		)
		(pin "1"
		)
		(pin "2"
		)
		(instances
			(project "environment-sensor"
				(path ""
					(reference "R24")
					(unit 1)
				)
			)
		)
	)
	(symbol
		(lib_id "antmicropower:PWR_FLAG")
		(at 209.55 99.06 0)
		(mirror y)
		(unit 1)
		(exclude_from_sim no)
		(in_bom yes)
		(on_board yes)
		(dnp no)
		(fields_autoplaced yes)
		(property "Reference" "#FLG03"
			(at 209.55 97.155 0)
			(effects
				(font
					(size 1.27 1.27)
				)
				(hide yes)
			)
		)
		(property "Value" "PWR_FLAG"
			(at 209.55 93.98 0)
			(effects
				(font
					(size 1.27 1.27)
				)
			)
		)
		(property "Footprint" ""
			(at 209.55 99.06 0)
			(effects
				(font
					(size 1.27 1.27)
				)
				(hide yes)
			)
		)
		(property "Datasheet" ""
			(at 209.55 99.06 0)
			(effects
				(font
					(size 1.27 1.27)
				)
				(hide yes)
			)
		)
		(property "Description" ""
			(at 209.55 99.06 0)
			(effects
				(font
					(size 1.27 1.27)
				)
				(hide yes)
			)
		)
		(pin "1"
		)
		(instances
			(project "environment-sensor"
				(path ""
					(reference "#FLG03")
					(unit 1)
				)
			)
		)
	)
	(symbol
		(lib_id "antmicroFerriteBeadsandChips:FB_120Z_2A_Murata-BLM18PG_0603")
		(at 223.52 101.6 0)
		(unit 1)
		(exclude_from_sim no)
		(in_bom yes)
		(on_board yes)
		(dnp no)
		(fields_autoplaced yes)
		(property "Reference" "FB3"
			(at 226.0219 95.25 0)
			(effects
				(font
					(size 1.27 1.27)
					(thickness 0.15)
				)
			)
		)
		(property "Value" "FB_120Z_2A_Murata-BLM18PG_0603"
			(at 238.76 104.14 0)
			(effects
				(font
					(size 1.27 1.27)
					(thickness 0.15)
				)
				(justify left bottom)
				(hide yes)
			)
		)
		(property "Footprint" "antmicro-footprints:FB_0603_1608Metric"
			(at 238.76 109.22 0)
			(effects
				(font
					(size 1.27 1.27)
					(thickness 0.15)
				)
				(justify left bottom)
				(hide yes)
			)
		)
		(property "Datasheet" "https://www.murata.com/en-us/products/productdata/8796738650142/ENFA0003.pdf"
			(at 238.76 111.76 0)
			(effects
				(font
					(size 1.27 1.27)
					(thickness 0.15)
				)
				(justify left bottom)
				(hide yes)
			)
		)
		(property "Description" "Ferrite Bead, 0603 [1608 Metric], 120 ohm, 2 A, BLM18P, 0.05 ohm, ± 25%, DC power line"
			(at 223.52 101.6 0)
			(effects
				(font
					(size 1.27 1.27)
				)
				(hide yes)
			)
		)
		(property "Val" "120Z/2A"
			(at 226.0219 97.79 0)
			(effects
				(font
					(size 1.27 1.27)
				)
			)
		)
		(property "MPN" "BLM18PG121SN1D"
			(at 238.76 114.3 0)
			(effects
				(font
					(size 1.27 1.27)
					(thickness 0.15)
				)
				(justify left bottom)
				(hide yes)
			)
		)
		(property "Manufacturer" "Murata"
			(at 238.76 116.84 0)
			(effects
				(font
					(size 1.27 1.27)
					(thickness 0.15)
				)
				(justify left bottom)
				(hide yes)
			)
		)
		(property "Current" ""
			(at 243.84 124.46 0)
			(effects
				(font
					(size 1.27 1.27)
					(thickness 0.15)
				)
				(justify left bottom)
				(hide yes)
			)
		)
		(property "Author" "Antmicro"
			(at 238.76 119.38 0)
			(effects
				(font
					(size 1.27 1.27)
					(thickness 0.15)
				)
				(justify left bottom)
				(hide yes)
			)
		)
		(property "License" "Apache-2.0"
			(at 238.76 121.92 0)
			(effects
				(font
					(size 1.27 1.27)
					(thickness 0.15)
				)
				(justify left bottom)
				(hide yes)
			)
		)
		(property "Public" "False"
			(at 243.84 116.84 0)
			(effects
				(font
					(size 1.27 1.27)
				)
				(justify left bottom)
				(hide yes)
			)
		)
		(pin "2"
		)
		(pin "1"
		)
		(instances
			(project "environment-sensor"
				(path ""
					(reference "FB3")
					(unit 1)
				)
			)
		)
	)
	(symbol
		(lib_id "antmicroTestPoints:TP_1.5mm_SMD")
		(at 147.32 247.65 180)
		(unit 1)
		(exclude_from_sim no)
		(in_bom yes)
		(on_board yes)
		(dnp no)
		(fields_autoplaced yes)
		(property "Reference" "TP2"
			(at 140.335 246.38 0)
			(effects
				(font
					(size 1.27 1.27)
					(thickness 0.15)
				)
			)
		)
		(property "Value" "TP_1.5mm_SMD"
			(at 132.08 240.03 0)
			(effects
				(font
					(size 1.27 1.27)
					(thickness 0.15)
				)
				(justify left bottom)
				(hide yes)
			)
		)
		(property "Footprint" "antmicro-footprints:TP_SMD_1.5mm"
			(at 132.08 237.49 0)
			(effects
				(font
					(size 1.27 1.27)
					(thickness 0.15)
				)
				(justify left bottom)
				(hide yes)
			)
		)
		(property "Datasheet" ""
			(at 132.08 234.95 0)
			(effects
				(font
					(size 1.27 1.27)
					(thickness 0.15)
				)
				(justify left bottom)
				(hide yes)
			)
		)
		(property "Description" "test point, SMT"
			(at 147.32 247.65 0)
			(effects
				(font
					(size 1.27 1.27)
				)
				(hide yes)
			)
		)
		(property "MPN" ""
			(at 147.32 247.65 0)
			(effects
				(font
					(size 1.27 1.27)
				)
				(hide yes)
			)
		)
		(property "Manufacturer" ""
			(at 147.32 247.65 0)
			(effects
				(font
					(size 1.27 1.27)
				)
				(hide yes)
			)
		)
		(property "Author" "Antmicro"
			(at 132.08 232.41 0)
			(effects
				(font
					(size 1.27 1.27)
					(thickness 0.15)
				)
				(justify left bottom)
				(hide yes)
			)
		)
		(property "License" "Apache-2.0"
			(at 132.08 229.87 0)
			(effects
				(font
					(size 1.27 1.27)
					(thickness 0.15)
				)
				(justify left bottom)
				(hide yes)
			)
		)
		(property "Public" "False"
			(at 132.08 227.33 0)
			(effects
				(font
					(size 1.27 1.27)
				)
				(justify left bottom)
				(hide yes)
			)
		)
		(pin "1"
		)
		(instances
			(project "environment-sensor"
				(path ""
					(reference "TP2")
					(unit 1)
				)
			)
		)
	)
	(symbol
		(lib_id "antmicropower:+3V3")
		(at 370.84 73.66 0)
		(mirror y)
		(unit 1)
		(exclude_from_sim no)
		(in_bom yes)
		(on_board yes)
		(dnp no)
		(fields_autoplaced yes)
		(property "Reference" "#PWR068"
			(at 370.84 77.47 0)
			(effects
				(font
					(size 1.27 1.27)
				)
				(hide yes)
			)
		)
		(property "Value" "+3V3"
			(at 373.38 68.58 0)
			(effects
				(font
					(size 1.27 1.27)
				)
				(justify left)
			)
		)
		(property "Footprint" ""
			(at 370.84 73.66 0)
			(effects
				(font
					(size 1.27 1.27)
				)
				(hide yes)
			)
		)
		(property "Datasheet" ""
			(at 370.84 73.66 0)
			(effects
				(font
					(size 1.27 1.27)
				)
				(hide yes)
			)
		)
		(property "Description" ""
			(at 370.84 73.66 0)
			(effects
				(font
					(size 1.27 1.27)
				)
				(hide yes)
			)
		)
		(property "Author" "Antmicro"
			(at 355.6 76.2 0)
			(effects
				(font
					(size 1.27 1.27)
					(thickness 0.15)
				)
				(justify left bottom)
				(hide yes)
			)
		)
		(property "License" "Apache-2.0"
			(at 355.6 78.74 0)
			(effects
				(font
					(size 1.27 1.27)
					(thickness 0.15)
				)
				(justify left bottom)
				(hide yes)
			)
		)
		(pin "1"
		)
		(instances
			(project "environment-sensor"
				(path ""
					(reference "#PWR068")
					(unit 1)
				)
			)
		)
	)
	(symbol
		(lib_id "antmicroTVSDiodes:ESD9X5.0ST5G")
		(at 227.33 273.05 90)
		(unit 1)
		(exclude_from_sim no)
		(in_bom yes)
		(on_board yes)
		(dnp no)
		(fields_autoplaced yes)
		(property "Reference" "D7"
			(at 231.14 267.6524 90)
			(effects
				(font
					(size 1.27 1.27)
					(thickness 0.15)
				)
				(justify right)
			)
		)
		(property "Value" "ESD9X5.0ST5G"
			(at 231.14 270.1924 90)
			(effects
				(font
					(size 1.27 1.27)
					(thickness 0.15)
				)
				(justify right)
			)
		)
		(property "Footprint" "antmicro-footprints:SOD-923"
			(at 234.95 251.46 0)
			(effects
				(font
					(size 1.27 1.27)
					(thickness 0.15)
				)
				(justify left bottom)
				(hide yes)
			)
		)
		(property "Datasheet" "https://www.onsemi.com/pdf/datasheet/esd9x3.3st5g-d.pdf"
			(at 237.49 251.46 0)
			(effects
				(font
					(size 1.27 1.27)
					(thickness 0.15)
				)
				(justify left bottom)
				(hide yes)
			)
		)
		(property "Description" "Unidirectional TVS, 30 kV,  SOD-923, 5 V, 65 pF"
			(at 227.33 273.05 0)
			(effects
				(font
					(size 1.27 1.27)
				)
				(hide yes)
			)
		)
		(property "Manufacturer" "ON Semiconductor"
			(at 240.03 251.46 0)
			(effects
				(font
					(size 1.27 1.27)
					(thickness 0.15)
				)
				(justify left bottom)
				(hide yes)
			)
		)
		(property "MPN" "ESD9X5.0ST5G"
			(at 242.57 251.46 0)
			(effects
				(font
					(size 1.27 1.27)
					(thickness 0.15)
				)
				(justify left bottom)
				(hide yes)
			)
		)
		(property "Author" "Antmicro"
			(at 245.11 251.46 0)
			(effects
				(font
					(size 1.27 1.27)
					(thickness 0.15)
				)
				(justify left bottom)
				(hide yes)
			)
		)
		(property "License" "Apache-2.0"
			(at 247.65 251.46 0)
			(effects
				(font
					(size 1.27 1.27)
					(thickness 0.15)
				)
				(justify left bottom)
				(hide yes)
			)
		)
		(property "Public" "False"
			(at 245.11 252.73 0)
			(effects
				(font
					(size 1.27 1.27)
				)
				(justify left bottom)
				(hide yes)
			)
		)
		(pin "1"
		)
		(pin "2"
		)
		(instances
			(project "environment-sensor"
				(path ""
					(reference "D7")
					(unit 1)
				)
			)
		)
	)
	(symbol
		(lib_id "antmicroTVSDiodes:ESD9X5.0ST5G")
		(at 99.06 105.41 90)
		(unit 1)
		(exclude_from_sim no)
		(in_bom yes)
		(on_board yes)
		(dnp no)
		(fields_autoplaced yes)
		(property "Reference" "D4"
			(at 102.87 100.0124 90)
			(effects
				(font
					(size 1.27 1.27)
					(thickness 0.15)
				)
				(justify right)
			)
		)
		(property "Value" "ESD9X5.0ST5G"
			(at 102.87 102.5524 90)
			(effects
				(font
					(size 1.27 1.27)
					(thickness 0.15)
				)
				(justify right)
			)
		)
		(property "Footprint" "antmicro-footprints:SOD-923"
			(at 106.68 83.82 0)
			(effects
				(font
					(size 1.27 1.27)
					(thickness 0.15)
				)
				(justify left bottom)
				(hide yes)
			)
		)
		(property "Datasheet" "https://www.onsemi.com/pdf/datasheet/esd9x3.3st5g-d.pdf"
			(at 109.22 83.82 0)
			(effects
				(font
					(size 1.27 1.27)
					(thickness 0.15)
				)
				(justify left bottom)
				(hide yes)
			)
		)
		(property "Description" "Unidirectional TVS, 30 kV,  SOD-923, 5 V, 65 pF"
			(at 99.06 105.41 0)
			(effects
				(font
					(size 1.27 1.27)
				)
				(hide yes)
			)
		)
		(property "Manufacturer" "ON Semiconductor"
			(at 111.76 83.82 0)
			(effects
				(font
					(size 1.27 1.27)
					(thickness 0.15)
				)
				(justify left bottom)
				(hide yes)
			)
		)
		(property "MPN" "ESD9X5.0ST5G"
			(at 114.3 83.82 0)
			(effects
				(font
					(size 1.27 1.27)
					(thickness 0.15)
				)
				(justify left bottom)
				(hide yes)
			)
		)
		(property "Author" "Antmicro"
			(at 116.84 83.82 0)
			(effects
				(font
					(size 1.27 1.27)
					(thickness 0.15)
				)
				(justify left bottom)
				(hide yes)
			)
		)
		(property "License" "Apache-2.0"
			(at 119.38 83.82 0)
			(effects
				(font
					(size 1.27 1.27)
					(thickness 0.15)
				)
				(justify left bottom)
				(hide yes)
			)
		)
		(property "Public" "False"
			(at 116.84 85.09 0)
			(effects
				(font
					(size 1.27 1.27)
				)
				(justify left bottom)
				(hide yes)
			)
		)
		(pin "1"
		)
		(pin "2"
		)
		(instances
			(project "environment-sensor"
				(path ""
					(reference "D4")
					(unit 1)
				)
			)
		)
	)
	(symbol
		(lib_id "antmicropower:GND")
		(at 375.92 179.07 0)
		(mirror y)
		(unit 1)
		(exclude_from_sim no)
		(in_bom yes)
		(on_board yes)
		(dnp no)
		(fields_autoplaced yes)
		(property "Reference" "#PWR070"
			(at 375.92 185.42 0)
			(effects
				(font
					(size 1.27 1.27)
				)
				(hide yes)
			)
		)
		(property "Value" "GND"
			(at 375.92 184.15 0)
			(effects
				(font
					(size 1.27 1.27)
				)
			)
		)
		(property "Footprint" ""
			(at 375.92 179.07 0)
			(effects
				(font
					(size 1.27 1.27)
				)
				(hide yes)
			)
		)
		(property "Datasheet" ""
			(at 375.92 179.07 0)
			(effects
				(font
					(size 1.27 1.27)
				)
				(hide yes)
			)
		)
		(property "Description" ""
			(at 375.92 179.07 0)
			(effects
				(font
					(size 1.27 1.27)
				)
				(hide yes)
			)
		)
		(property "Author" "Antmicro"
			(at 367.03 186.69 0)
			(effects
				(font
					(size 1.27 1.27)
					(thickness 0.15)
				)
				(justify left bottom)
				(hide yes)
			)
		)
		(property "License" "Apache-2.0"
			(at 367.03 189.23 0)
			(effects
				(font
					(size 1.27 1.27)
					(thickness 0.15)
				)
				(justify left bottom)
				(hide yes)
			)
		)
		(pin "1"
		)
		(instances
			(project "environment-sensor"
				(path ""
					(reference "#PWR070")
					(unit 1)
				)
			)
		)
	)
	(symbol
		(lib_id "antmicroResistors0402:R_100k_0402")
		(at 306.07 152.4 90)
		(unit 1)
		(exclude_from_sim no)
		(in_bom no)
		(on_board yes)
		(dnp yes)
		(fields_autoplaced yes)
		(property "Reference" "R30"
			(at 308.61 148.5899 90)
			(effects
				(font
					(size 1.27 1.27)
					(thickness 0.15)
				)
				(justify right)
			)
		)
		(property "Value" "R_100k_0402"
			(at 318.77 132.08 0)
			(effects
				(font
					(size 1.27 1.27)
					(thickness 0.15)
				)
				(justify left bottom)
				(hide yes)
			)
		)
		(property "Footprint" "antmicro-footprints:R_0402_1005Metric"
			(at 321.31 132.08 0)
			(effects
				(font
					(size 1.27 1.27)
					(thickness 0.15)
				)
				(justify left bottom)
				(hide yes)
			)
		)
		(property "Datasheet" "https://www.bourns.com/docs/product-datasheets/cr.pdf"
			(at 323.85 132.08 0)
			(effects
				(font
					(size 1.27 1.27)
					(thickness 0.15)
				)
				(justify left bottom)
				(hide yes)
			)
		)
		(property "Description" "SMD Chip Resistor, 100 kohm, ± 1%, 62.5 mW, 0402 [1005 Metric], Thick Film, General Purpose"
			(at 306.07 152.4 0)
			(effects
				(font
					(size 1.27 1.27)
				)
				(hide yes)
			)
		)
		(property "Manufacturer" "Bourns"
			(at 328.93 132.08 0)
			(effects
				(font
					(size 1.27 1.27)
					(thickness 0.15)
				)
				(justify left bottom)
				(hide yes)
			)
		)
		(property "MPN" "CR0402-FX-1003GLF"
			(at 326.39 132.08 0)
			(effects
				(font
					(size 1.27 1.27)
					(thickness 0.15)
				)
				(justify left bottom)
				(hide yes)
			)
		)
		(property "Val" "100k"
			(at 308.61 151.1299 90)
			(effects
				(font
					(size 1.27 1.27)
					(thickness 0.15)
				)
				(justify right)
			)
		)
		(property "License" "Apache-2.0"
			(at 331.47 132.08 0)
			(effects
				(font
					(size 1.27 1.27)
					(thickness 0.15)
				)
				(justify left bottom)
				(hide yes)
			)
		)
		(property "Author" "Antmicro"
			(at 334.01 132.08 0)
			(effects
				(font
					(size 1.27 1.27)
					(thickness 0.15)
				)
				(justify left bottom)
				(hide yes)
			)
		)
		(property "Tolerance" "1%"
			(at 316.23 132.08 0)
			(effects
				(font
					(size 1.27 1.27)
				)
				(justify left bottom)
				(hide yes)
			)
		)
		(property "Public" "False"
			(at 336.55 132.08 0)
			(effects
				(font
					(size 1.27 1.27)
				)
				(justify left bottom)
				(hide yes)
			)
		)
		(pin "1"
		)
		(pin "2"
		)
		(instances
			(project "environment-sensor"
				(path ""
					(reference "R30")
					(unit 1)
				)
			)
		)
	)
	(symbol
		(lib_id "antmicropower:GND")
		(at 316.23 63.5 0)
		(mirror y)
		(unit 1)
		(exclude_from_sim no)
		(in_bom yes)
		(on_board yes)
		(dnp no)
		(fields_autoplaced yes)
		(property "Reference" "#PWR060"
			(at 316.23 69.85 0)
			(effects
				(font
					(size 1.27 1.27)
				)
				(hide yes)
			)
		)
		(property "Value" "GND"
			(at 313.69 64.7699 0)
			(effects
				(font
					(size 1.27 1.27)
				)
				(justify left)
			)
		)
		(property "Footprint" ""
			(at 316.23 63.5 0)
			(effects
				(font
					(size 1.27 1.27)
				)
				(hide yes)
			)
		)
		(property "Datasheet" ""
			(at 316.23 63.5 0)
			(effects
				(font
					(size 1.27 1.27)
				)
				(hide yes)
			)
		)
		(property "Description" ""
			(at 316.23 63.5 0)
			(effects
				(font
					(size 1.27 1.27)
				)
				(hide yes)
			)
		)
		(property "Author" "Antmicro"
			(at 307.34 71.12 0)
			(effects
				(font
					(size 1.27 1.27)
					(thickness 0.15)
				)
				(justify left bottom)
				(hide yes)
			)
		)
		(property "License" "Apache-2.0"
			(at 307.34 73.66 0)
			(effects
				(font
					(size 1.27 1.27)
					(thickness 0.15)
				)
				(justify left bottom)
				(hide yes)
			)
		)
		(pin "1"
		)
		(instances
			(project "environment-sensor"
				(path ""
					(reference "#PWR060")
					(unit 1)
				)
			)
		)
	)
	(symbol
		(lib_id "antmicroResistors0402:R_0R_0402")
		(at 101.6 200.66 0)
		(unit 1)
		(exclude_from_sim no)
		(in_bom yes)
		(on_board yes)
		(dnp no)
		(fields_autoplaced yes)
		(property "Reference" "R10"
			(at 100.33 199.39 0)
			(effects
				(font
					(size 1.27 1.27)
					(thickness 0.15)
				)
			)
		)
		(property "Value" "R_0R_0402"
			(at 121.92 213.36 0)
			(effects
				(font
					(size 1.27 1.27)
					(thickness 0.15)
				)
				(justify left bottom)
				(hide yes)
			)
		)
		(property "Footprint" "antmicro-footprints:R_0402_1005Metric"
			(at 121.92 215.9 0)
			(effects
				(font
					(size 1.27 1.27)
					(thickness 0.15)
				)
				(justify left bottom)
				(hide yes)
			)
		)
		(property "Datasheet" "https://industrial.panasonic.com/cdbs/www-data/pdf/RDA0000/AOA0000C301.pdf"
			(at 121.92 218.44 0)
			(effects
				(font
					(size 1.27 1.27)
					(thickness 0.15)
				)
				(justify left bottom)
				(hide yes)
			)
		)
		(property "Description" "SMD Chip Resistor, Jumper, 0 ohm, 100 mW, 0402 [1005 Metric], Thick Film, General Purpose"
			(at 101.6 200.66 0)
			(effects
				(font
					(size 1.27 1.27)
				)
				(hide yes)
			)
		)
		(property "Manufacturer" "Panasonic"
			(at 121.92 223.52 0)
			(effects
				(font
					(size 1.27 1.27)
					(thickness 0.15)
				)
				(justify left bottom)
				(hide yes)
			)
		)
		(property "MPN" "ERJ2GE0R00X"
			(at 121.92 220.98 0)
			(effects
				(font
					(size 1.27 1.27)
					(thickness 0.15)
				)
				(justify left bottom)
				(hide yes)
			)
		)
		(property "Val" "0R"
			(at 107.315 199.39 0)
			(effects
				(font
					(size 1.27 1.27)
					(thickness 0.15)
				)
			)
		)
		(property "License" "Apache-2.0"
			(at 121.92 226.06 0)
			(effects
				(font
					(size 1.27 1.27)
					(thickness 0.15)
				)
				(justify left bottom)
				(hide yes)
			)
		)
		(property "Author" "Antmicro"
			(at 121.92 228.6 0)
			(effects
				(font
					(size 1.27 1.27)
					(thickness 0.15)
				)
				(justify left bottom)
				(hide yes)
			)
		)
		(property "Tolerance" "~"
			(at 121.92 210.82 0)
			(effects
				(font
					(size 1.27 1.27)
				)
				(justify left bottom)
				(hide yes)
			)
		)
		(property "Current" "1A"
			(at 104.14 200.66 0)
			(effects
				(font
					(size 1.27 1.27)
					(thickness 0.15)
				)
				(hide yes)
			)
		)
		(property "Public" "False"
			(at 121.92 231.14 0)
			(effects
				(font
					(size 1.27 1.27)
				)
				(justify left bottom)
				(hide yes)
			)
		)
		(pin "1"
		)
		(pin "2"
		)
		(instances
			(project "environment-sensor"
				(path ""
					(reference "R10")
					(unit 1)
				)
			)
		)
	)
	(symbol
		(lib_id "antmicroTVSDiodes:TPD2E009_SOT-9X3")
		(at 208.28 257.81 270)
		(unit 1)
		(exclude_from_sim no)
		(in_bom yes)
		(on_board yes)
		(dnp no)
		(fields_autoplaced yes)
		(property "Reference" "D6"
			(at 204.47 269.24 90)
			(effects
				(font
					(size 1.27 1.27)
					(thickness 0.15)
				)
				(justify left)
			)
		)
		(property "Value" "TPD2E009_SOT-9X3"
			(at 193.04 274.32 90)
			(effects
				(font
					(size 1.27 1.27)
					(thickness 0.15)
				)
				(justify left)
			)
		)
		(property "Footprint" "antmicro-footprints:SOT-723"
			(at 203.2 273.05 0)
			(effects
				(font
					(size 1.27 1.27)
					(thickness 0.15)
				)
				(justify left bottom)
				(hide yes)
			)
		)
		(property "Datasheet" "https://www.ti.com/lit/ds/symlink/tpd2e009.pdf?ts=1597910439511&ref_url=https%253A%252F%252Fwww.google.com%252F"
			(at 200.66 273.05 0)
			(effects
				(font
					(size 1.27 1.27)
					(thickness 0.15)
				)
				(justify left bottom)
				(hide yes)
			)
		)
		(property "Description" "TVS diode array, 8 kV, SOT-723, 5.5 V, 0.9 pF"
			(at 208.28 257.81 0)
			(effects
				(font
					(size 1.27 1.27)
				)
				(hide yes)
			)
		)
		(property "MPN" "TPD2E009DRTR"
			(at 198.12 273.05 0)
			(effects
				(font
					(size 1.27 1.27)
					(thickness 0.15)
				)
				(justify left bottom)
				(hide yes)
			)
		)
		(property "Manufacturer" "Texas Instruments"
			(at 195.58 273.05 0)
			(effects
				(font
					(size 1.27 1.27)
					(thickness 0.15)
				)
				(justify left bottom)
				(hide yes)
			)
		)
		(property "Author" "Antmicro"
			(at 193.04 273.05 0)
			(effects
				(font
					(size 1.27 1.27)
					(thickness 0.15)
				)
				(justify left bottom)
				(hide yes)
			)
		)
		(property "License" "Apache-2.0"
			(at 190.5 273.05 0)
			(effects
				(font
					(size 1.27 1.27)
					(thickness 0.15)
				)
				(justify left bottom)
				(hide yes)
			)
		)
		(pin "1"
		)
		(pin "2"
		)
		(pin "3"
		)
		(instances
			(project "environment-sensor"
				(path ""
					(reference "D6")
					(unit 1)
				)
			)
		)
	)
	(symbol
		(lib_id "antmicropower:PWR_FLAG")
		(at 161.29 41.91 0)
		(unit 1)
		(exclude_from_sim no)
		(in_bom yes)
		(on_board yes)
		(dnp no)
		(fields_autoplaced yes)
		(property "Reference" "#FLG01"
			(at 161.29 40.005 0)
			(effects
				(font
					(size 1.27 1.27)
				)
				(hide yes)
			)
		)
		(property "Value" "PWR_FLAG"
			(at 161.29 36.195 0)
			(effects
				(font
					(size 1.27 1.27)
				)
			)
		)
		(property "Footprint" ""
			(at 161.29 41.91 0)
			(effects
				(font
					(size 1.27 1.27)
				)
				(hide yes)
			)
		)
		(property "Datasheet" ""
			(at 161.29 41.91 0)
			(effects
				(font
					(size 1.27 1.27)
				)
				(hide yes)
			)
		)
		(property "Description" ""
			(at 161.29 41.91 0)
			(effects
				(font
					(size 1.27 1.27)
				)
				(hide yes)
			)
		)
		(pin "1"
		)
		(instances
			(project "environment-sensor"
				(path ""
					(reference "#FLG01")
					(unit 1)
				)
			)
		)
	)
	(symbol
		(lib_id "antmicropower:GND")
		(at 364.49 240.03 0)
		(mirror y)
		(unit 1)
		(exclude_from_sim no)
		(in_bom yes)
		(on_board yes)
		(dnp no)
		(fields_autoplaced yes)
		(property "Reference" "#PWR069"
			(at 364.49 246.38 0)
			(effects
				(font
					(size 1.27 1.27)
				)
				(hide yes)
			)
		)
		(property "Value" "GND"
			(at 364.49 245.11 0)
			(effects
				(font
					(size 1.27 1.27)
				)
			)
		)
		(property "Footprint" ""
			(at 364.49 240.03 0)
			(effects
				(font
					(size 1.27 1.27)
				)
				(hide yes)
			)
		)
		(property "Datasheet" ""
			(at 364.49 240.03 0)
			(effects
				(font
					(size 1.27 1.27)
				)
				(hide yes)
			)
		)
		(property "Description" ""
			(at 364.49 240.03 0)
			(effects
				(font
					(size 1.27 1.27)
				)
				(hide yes)
			)
		)
		(property "Author" "Antmicro"
			(at 355.6 247.65 0)
			(effects
				(font
					(size 1.27 1.27)
					(thickness 0.15)
				)
				(justify left bottom)
				(hide yes)
			)
		)
		(property "License" "Apache-2.0"
			(at 355.6 250.19 0)
			(effects
				(font
					(size 1.27 1.27)
					(thickness 0.15)
				)
				(justify left bottom)
				(hide yes)
			)
		)
		(pin "1"
		)
		(instances
			(project "environment-sensor"
				(path ""
					(reference "#PWR069")
					(unit 1)
				)
			)
		)
	)
	(symbol
		(lib_id "antmicroCapacitors0402:C_4u7_0402")
		(at 300.99 116.84 270)
		(mirror x)
		(unit 1)
		(exclude_from_sim no)
		(in_bom yes)
		(on_board yes)
		(dnp no)
		(fields_autoplaced yes)
		(property "Reference" "C9"
			(at 298.45 113.0235 90)
			(effects
				(font
					(size 1.27 1.27)
					(thickness 0.15)
				)
				(justify right)
			)
		)
		(property "Value" "C_4u7_0402"
			(at 290.83 96.52 0)
			(effects
				(font
					(size 1.27 1.27)
					(thickness 0.15)
				)
				(justify left bottom)
				(hide yes)
			)
		)
		(property "Footprint" "antmicro-footprints:C_0402_1005Metric"
			(at 288.29 96.52 0)
			(effects
				(font
					(size 1.27 1.27)
					(thickness 0.15)
				)
				(justify left bottom)
				(hide yes)
			)
		)
		(property "Datasheet" "https://www.murata.com/products/productdetail?partno=GRM155R61A475MEAA%23"
			(at 285.75 96.52 0)
			(effects
				(font
					(size 1.27 1.27)
					(thickness 0.15)
				)
				(justify left bottom)
				(hide yes)
			)
		)
		(property "Description" "SMD Multilayer Ceramic Capacitor, 4.7 µF, 10 V, 0402 [1005 Metric], ± 20%, X5R, GRM Series"
			(at 300.99 116.84 0)
			(effects
				(font
					(size 1.27 1.27)
				)
				(hide yes)
			)
		)
		(property "Manufacturer" "Murata"
			(at 280.67 96.52 0)
			(effects
				(font
					(size 1.27 1.27)
					(thickness 0.15)
				)
				(justify left bottom)
				(hide yes)
			)
		)
		(property "MPN" "GRM155R61A475MEAAD"
			(at 283.21 96.52 0)
			(effects
				(font
					(size 1.27 1.27)
					(thickness 0.15)
				)
				(justify left bottom)
				(hide yes)
			)
		)
		(property "Val" "4u7"
			(at 298.45 115.5635 90)
			(effects
				(font
					(size 1.27 1.27)
					(thickness 0.15)
				)
				(justify right)
			)
		)
		(property "License" "Apache-2.0"
			(at 278.13 96.52 0)
			(effects
				(font
					(size 1.27 1.27)
					(thickness 0.15)
				)
				(justify left bottom)
				(hide yes)
			)
		)
		(property "Author" "Antmicro"
			(at 275.59 96.52 0)
			(effects
				(font
					(size 1.27 1.27)
					(thickness 0.15)
				)
				(justify left bottom)
				(hide yes)
			)
		)
		(property "Voltage" ""
			(at 273.05 96.52 0)
			(effects
				(font
					(size 1.27 1.27)
				)
				(justify left bottom)
				(hide yes)
			)
		)
		(property "Dielectric" ""
			(at 270.51 96.52 0)
			(effects
				(font
					(size 1.27 1.27)
				)
				(justify left bottom)
				(hide yes)
			)
		)
		(property "Public" "False"
			(at 267.97 96.52 0)
			(effects
				(font
					(size 1.27 1.27)
				)
				(justify left bottom)
				(hide yes)
			)
		)
		(pin "1"
		)
		(pin "2"
		)
		(instances
			(project "environment-sensor"
				(path ""
					(reference "C9")
					(unit 1)
				)
			)
		)
	)
	(symbol
		(lib_id "antmicroResistors0402:R_5k1_0402")
		(at 381 45.72 90)
		(unit 1)
		(exclude_from_sim no)
		(in_bom yes)
		(on_board yes)
		(dnp no)
		(fields_autoplaced yes)
		(property "Reference" "R37"
			(at 383.54 41.9099 90)
			(effects
				(font
					(size 1.27 1.27)
					(thickness 0.15)
				)
				(justify right)
			)
		)
		(property "Value" "R_5k1_0402"
			(at 393.7 25.4 0)
			(effects
				(font
					(size 1.27 1.27)
					(thickness 0.15)
				)
				(justify left bottom)
				(hide yes)
			)
		)
		(property "Footprint" "antmicro-footprints:R_0402_1005Metric"
			(at 396.24 25.4 0)
			(effects
				(font
					(size 1.27 1.27)
					(thickness 0.15)
				)
				(justify left bottom)
				(hide yes)
			)
		)
		(property "Datasheet" "https://www.bourns.com/docs/product-datasheets/cr.pdf"
			(at 398.78 25.4 0)
			(effects
				(font
					(size 1.27 1.27)
					(thickness 0.15)
				)
				(justify left bottom)
				(hide yes)
			)
		)
		(property "Description" "SMD Chip Resistor, 5.1 kohm, ± 1%, 63 mW, 0402 [1005 Metric], Thick Film, General Purpose"
			(at 381 45.72 0)
			(effects
				(font
					(size 1.27 1.27)
				)
				(hide yes)
			)
		)
		(property "Manufacturer" "Bourns"
			(at 403.86 25.4 0)
			(effects
				(font
					(size 1.27 1.27)
					(thickness 0.15)
				)
				(justify left bottom)
				(hide yes)
			)
		)
		(property "MPN" "CR0402-FX-5101GLF"
			(at 401.32 25.4 0)
			(effects
				(font
					(size 1.27 1.27)
					(thickness 0.15)
				)
				(justify left bottom)
				(hide yes)
			)
		)
		(property "Val" "5k1"
			(at 383.54 44.4499 90)
			(effects
				(font
					(size 1.27 1.27)
					(thickness 0.15)
				)
				(justify right)
			)
		)
		(property "License" "Apache-2.0"
			(at 406.4 25.4 0)
			(effects
				(font
					(size 1.27 1.27)
					(thickness 0.15)
				)
				(justify left bottom)
				(hide yes)
			)
		)
		(property "Author" "Antmicro"
			(at 408.94 25.4 0)
			(effects
				(font
					(size 1.27 1.27)
					(thickness 0.15)
				)
				(justify left bottom)
				(hide yes)
			)
		)
		(property "Tolerance" "1%"
			(at 391.16 25.4 0)
			(effects
				(font
					(size 1.27 1.27)
				)
				(justify left bottom)
				(hide yes)
			)
		)
		(property "Public" "False"
			(at 411.48 25.4 0)
			(effects
				(font
					(size 1.27 1.27)
				)
				(justify left bottom)
				(hide yes)
			)
		)
		(pin "1"
		)
		(pin "2"
		)
		(instances
			(project "environment-sensor"
				(path ""
					(reference "R37")
					(unit 1)
				)
			)
		)
	)
	(symbol
		(lib_id "antmicroCapacitors0402:C_100n_0402")
		(at 215.9 266.7 270)
		(unit 1)
		(exclude_from_sim no)
		(in_bom yes)
		(on_board yes)
		(dnp no)
		(fields_autoplaced yes)
		(property "Reference" "C13"
			(at 218.44 267.9762 90)
			(effects
				(font
					(size 1.27 1.27)
					(thickness 0.15)
				)
				(justify left)
			)
		)
		(property "Value" "C_100n_0402"
			(at 205.74 287.02 0)
			(effects
				(font
					(size 1.27 1.27)
					(thickness 0.15)
				)
				(justify left bottom)
				(hide yes)
			)
		)
		(property "Footprint" "antmicro-footprints:C_0402_1005Metric"
			(at 203.2 287.02 0)
			(effects
				(font
					(size 1.27 1.27)
					(thickness 0.15)
				)
				(justify left bottom)
				(hide yes)
			)
		)
		(property "Datasheet" "https://www.murata.com/products/productdetail?partno=GRM155R61H104KE14%23"
			(at 200.66 287.02 0)
			(effects
				(font
					(size 1.27 1.27)
					(thickness 0.15)
				)
				(justify left bottom)
				(hide yes)
			)
		)
		(property "Description" "SMD Multilayer Ceramic Capacitor, 0.1 µF, 50 V, 0402 [1005 Metric], ± 10%, X5R, GRM Series"
			(at 215.9 266.7 0)
			(effects
				(font
					(size 1.27 1.27)
				)
				(hide yes)
			)
		)
		(property "Manufacturer" "Murata"
			(at 195.58 287.02 0)
			(effects
				(font
					(size 1.27 1.27)
					(thickness 0.15)
				)
				(justify left bottom)
				(hide yes)
			)
		)
		(property "MPN" "GRM155R61H104KE14D"
			(at 198.12 287.02 0)
			(effects
				(font
					(size 1.27 1.27)
					(thickness 0.15)
				)
				(justify left bottom)
				(hide yes)
			)
		)
		(property "Val" "100n"
			(at 218.44 270.5162 90)
			(effects
				(font
					(size 1.27 1.27)
					(thickness 0.15)
				)
				(justify left)
			)
		)
		(property "License" "Apache-2.0"
			(at 193.04 287.02 0)
			(effects
				(font
					(size 1.27 1.27)
					(thickness 0.15)
				)
				(justify left bottom)
				(hide yes)
			)
		)
		(property "Author" "Antmicro"
			(at 190.5 287.02 0)
			(effects
				(font
					(size 1.27 1.27)
					(thickness 0.15)
				)
				(justify left bottom)
				(hide yes)
			)
		)
		(property "Voltage" "50V"
			(at 187.96 287.02 0)
			(effects
				(font
					(size 1.27 1.27)
				)
				(justify left bottom)
				(hide yes)
			)
		)
		(property "Dielectric" "X5R"
			(at 185.42 287.02 0)
			(effects
				(font
					(size 1.27 1.27)
				)
				(justify left bottom)
				(hide yes)
			)
		)
		(property "Public" "False"
			(at 182.88 287.02 0)
			(effects
				(font
					(size 1.27 1.27)
				)
				(justify left bottom)
				(hide yes)
			)
		)
		(pin "1"
		)
		(pin "2"
		)
		(instances
			(project "environment-sensor"
				(path ""
					(reference "C13")
					(unit 1)
				)
			)
		)
	)
	(symbol
		(lib_id "antmicroCapacitors0402:C_100n_0402")
		(at 353.06 233.68 270)
		(unit 1)
		(exclude_from_sim no)
		(in_bom yes)
		(on_board yes)
		(dnp no)
		(fields_autoplaced yes)
		(property "Reference" "C25"
			(at 355.6 234.9562 90)
			(effects
				(font
					(size 1.27 1.27)
					(thickness 0.15)
				)
				(justify left)
			)
		)
		(property "Value" "C_100n_0402"
			(at 342.9 254 0)
			(effects
				(font
					(size 1.27 1.27)
					(thickness 0.15)
				)
				(justify left bottom)
				(hide yes)
			)
		)
		(property "Footprint" "antmicro-footprints:C_0402_1005Metric"
			(at 340.36 254 0)
			(effects
				(font
					(size 1.27 1.27)
					(thickness 0.15)
				)
				(justify left bottom)
				(hide yes)
			)
		)
		(property "Datasheet" "https://www.murata.com/products/productdetail?partno=GRM155R61H104KE14%23"
			(at 337.82 254 0)
			(effects
				(font
					(size 1.27 1.27)
					(thickness 0.15)
				)
				(justify left bottom)
				(hide yes)
			)
		)
		(property "Description" "SMD Multilayer Ceramic Capacitor, 0.1 µF, 50 V, 0402 [1005 Metric], ± 10%, X5R, GRM Series"
			(at 353.06 233.68 0)
			(effects
				(font
					(size 1.27 1.27)
				)
				(hide yes)
			)
		)
		(property "Manufacturer" "Murata"
			(at 332.74 254 0)
			(effects
				(font
					(size 1.27 1.27)
					(thickness 0.15)
				)
				(justify left bottom)
				(hide yes)
			)
		)
		(property "MPN" "GRM155R61H104KE14D"
			(at 335.28 254 0)
			(effects
				(font
					(size 1.27 1.27)
					(thickness 0.15)
				)
				(justify left bottom)
				(hide yes)
			)
		)
		(property "Val" "100n"
			(at 355.6 237.4962 90)
			(effects
				(font
					(size 1.27 1.27)
					(thickness 0.15)
				)
				(justify left)
			)
		)
		(property "License" "Apache-2.0"
			(at 330.2 254 0)
			(effects
				(font
					(size 1.27 1.27)
					(thickness 0.15)
				)
				(justify left bottom)
				(hide yes)
			)
		)
		(property "Author" "Antmicro"
			(at 327.66 254 0)
			(effects
				(font
					(size 1.27 1.27)
					(thickness 0.15)
				)
				(justify left bottom)
				(hide yes)
			)
		)
		(property "Voltage" "50V"
			(at 325.12 254 0)
			(effects
				(font
					(size 1.27 1.27)
				)
				(justify left bottom)
				(hide yes)
			)
		)
		(property "Dielectric" "X5R"
			(at 322.58 254 0)
			(effects
				(font
					(size 1.27 1.27)
				)
				(justify left bottom)
				(hide yes)
			)
		)
		(property "Public" "False"
			(at 320.04 254 0)
			(effects
				(font
					(size 1.27 1.27)
				)
				(justify left bottom)
				(hide yes)
			)
		)
		(pin "1"
		)
		(pin "2"
		)
		(instances
			(project "environment-sensor"
				(path ""
					(reference "C25")
					(unit 1)
				)
			)
		)
	)
	(symbol
		(lib_id "antmicroCapacitors0402:C_100n_0402")
		(at 251.46 116.84 90)
		(unit 1)
		(exclude_from_sim no)
		(in_bom yes)
		(on_board yes)
		(dnp no)
		(fields_autoplaced yes)
		(property "Reference" "C17"
			(at 248.92 113.0235 90)
			(effects
				(font
					(size 1.27 1.27)
					(thickness 0.15)
				)
				(justify left)
			)
		)
		(property "Value" "C_100n_0402"
			(at 261.62 96.52 0)
			(effects
				(font
					(size 1.27 1.27)
					(thickness 0.15)
				)
				(justify left bottom)
				(hide yes)
			)
		)
		(property "Footprint" "antmicro-footprints:C_0402_1005Metric"
			(at 264.16 96.52 0)
			(effects
				(font
					(size 1.27 1.27)
					(thickness 0.15)
				)
				(justify left bottom)
				(hide yes)
			)
		)
		(property "Datasheet" "https://www.murata.com/products/productdetail?partno=GRM155R61H104KE14%23"
			(at 266.7 96.52 0)
			(effects
				(font
					(size 1.27 1.27)
					(thickness 0.15)
				)
				(justify left bottom)
				(hide yes)
			)
		)
		(property "Description" "SMD Multilayer Ceramic Capacitor, 0.1 µF, 50 V, 0402 [1005 Metric], ± 10%, X5R, GRM Series"
			(at 251.46 116.84 0)
			(effects
				(font
					(size 1.27 1.27)
				)
				(hide yes)
			)
		)
		(property "Manufacturer" "Murata"
			(at 271.78 96.52 0)
			(effects
				(font
					(size 1.27 1.27)
					(thickness 0.15)
				)
				(justify left bottom)
				(hide yes)
			)
		)
		(property "MPN" "GRM155R61H104KE14D"
			(at 269.24 96.52 0)
			(effects
				(font
					(size 1.27 1.27)
					(thickness 0.15)
				)
				(justify left bottom)
				(hide yes)
			)
		)
		(property "Val" "100n"
			(at 248.92 115.5635 90)
			(effects
				(font
					(size 1.27 1.27)
					(thickness 0.15)
				)
				(justify left)
			)
		)
		(property "License" "Apache-2.0"
			(at 274.32 96.52 0)
			(effects
				(font
					(size 1.27 1.27)
					(thickness 0.15)
				)
				(justify left bottom)
				(hide yes)
			)
		)
		(property "Author" "Antmicro"
			(at 276.86 96.52 0)
			(effects
				(font
					(size 1.27 1.27)
					(thickness 0.15)
				)
				(justify left bottom)
				(hide yes)
			)
		)
		(property "Voltage" "50V"
			(at 279.4 96.52 0)
			(effects
				(font
					(size 1.27 1.27)
				)
				(justify left bottom)
				(hide yes)
			)
		)
		(property "Dielectric" "X5R"
			(at 281.94 96.52 0)
			(effects
				(font
					(size 1.27 1.27)
				)
				(justify left bottom)
				(hide yes)
			)
		)
		(property "Public" "False"
			(at 284.48 96.52 0)
			(effects
				(font
					(size 1.27 1.27)
				)
				(justify left bottom)
				(hide yes)
			)
		)
		(pin "1"
		)
		(pin "2"
		)
		(instances
			(project "environment-sensor"
				(path ""
					(reference "C17")
					(unit 1)
				)
			)
		)
	)
	(symbol
		(lib_id "antmicropower:GND")
		(at 177.8 64.77 0)
		(unit 1)
		(exclude_from_sim no)
		(in_bom yes)
		(on_board yes)
		(dnp no)
		(fields_autoplaced yes)
		(property "Reference" "#PWR022"
			(at 177.8 71.12 0)
			(effects
				(font
					(size 1.27 1.27)
				)
				(hide yes)
			)
		)
		(property "Value" "GND"
			(at 177.8 69.85 0)
			(effects
				(font
					(size 1.27 1.27)
				)
			)
		)
		(property "Footprint" ""
			(at 177.8 64.77 0)
			(effects
				(font
					(size 1.27 1.27)
				)
				(hide yes)
			)
		)
		(property "Datasheet" ""
			(at 177.8 64.77 0)
			(effects
				(font
					(size 1.27 1.27)
				)
				(hide yes)
			)
		)
		(property "Description" ""
			(at 177.8 64.77 0)
			(effects
				(font
					(size 1.27 1.27)
				)
				(hide yes)
			)
		)
		(property "Author" "Antmicro"
			(at 186.69 72.39 0)
			(effects
				(font
					(size 1.27 1.27)
					(thickness 0.15)
				)
				(justify left bottom)
				(hide yes)
			)
		)
		(property "License" "Apache-2.0"
			(at 186.69 74.93 0)
			(effects
				(font
					(size 1.27 1.27)
					(thickness 0.15)
				)
				(justify left bottom)
				(hide yes)
			)
		)
		(pin "1"
		)
		(instances
			(project "environment-sensor"
				(path ""
					(reference "#PWR022")
					(unit 1)
				)
			)
		)
	)
	(symbol
		(lib_id "antmicroTestPoints:TP_1mm_SMD")
		(at 386.08 73.66 90)
		(unit 1)
		(exclude_from_sim no)
		(in_bom yes)
		(on_board yes)
		(dnp no)
		(fields_autoplaced yes)
		(property "Reference" "TP10"
			(at 387.35 69.85 90)
			(effects
				(font
					(size 1.27 1.27)
					(thickness 0.15)
				)
				(justify right)
			)
		)
		(property "Value" "TP_1mm_SMD"
			(at 388.62 71.7549 90)
			(effects
				(font
					(size 1.27 1.27)
					(thickness 0.15)
				)
				(justify right)
				(hide yes)
			)
		)
		(property "Footprint" "antmicro-footprints:TP_SMD_1mm"
			(at 396.24 58.42 0)
			(effects
				(font
					(size 1.27 1.27)
					(thickness 0.15)
				)
				(justify left bottom)
				(hide yes)
			)
		)
		(property "Datasheet" ""
			(at 398.78 58.42 0)
			(effects
				(font
					(size 1.27 1.27)
					(thickness 0.15)
				)
				(justify left bottom)
				(hide yes)
			)
		)
		(property "Description" "Test point 1mm SMD"
			(at 386.08 73.66 0)
			(effects
				(font
					(size 1.27 1.27)
				)
				(hide yes)
			)
		)
		(property "Author" "Antmicro"
			(at 401.32 58.42 0)
			(effects
				(font
					(size 1.27 1.27)
					(thickness 0.15)
				)
				(justify left bottom)
				(hide yes)
			)
		)
		(property "License" "Apache-2.0"
			(at 403.86 58.42 0)
			(effects
				(font
					(size 1.27 1.27)
					(thickness 0.15)
				)
				(justify left bottom)
				(hide yes)
			)
		)
		(property "MPN" ""
			(at 386.08 73.66 0)
			(effects
				(font
					(size 1.27 1.27)
				)
				(hide yes)
			)
		)
		(property "Manufacturer" ""
			(at 386.08 73.66 0)
			(effects
				(font
					(size 1.27 1.27)
				)
				(hide yes)
			)
		)
		(property "Public" "False"
			(at 406.4 58.42 0)
			(effects
				(font
					(size 1.27 1.27)
				)
				(justify left bottom)
				(hide yes)
			)
		)
		(pin "1"
		)
		(instances
			(project "environment-sensor"
				(path ""
					(reference "TP10")
					(unit 1)
				)
			)
		)
	)
	(symbol
		(lib_id "antmicroResistors0402:R_100k_0402")
		(at 316.23 60.96 270)
		(mirror x)
		(unit 1)
		(exclude_from_sim no)
		(in_bom yes)
		(on_board yes)
		(dnp no)
		(fields_autoplaced yes)
		(property "Reference" "R34"
			(at 318.77 57.1499 90)
			(effects
				(font
					(size 1.27 1.27)
					(thickness 0.15)
				)
				(justify left)
			)
		)
		(property "Value" "R_100k_0402"
			(at 303.53 40.64 0)
			(effects
				(font
					(size 1.27 1.27)
					(thickness 0.15)
				)
				(justify left bottom)
				(hide yes)
			)
		)
		(property "Footprint" "antmicro-footprints:R_0402_1005Metric"
			(at 300.99 40.64 0)
			(effects
				(font
					(size 1.27 1.27)
					(thickness 0.15)
				)
				(justify left bottom)
				(hide yes)
			)
		)
		(property "Datasheet" "https://www.bourns.com/docs/product-datasheets/cr.pdf"
			(at 298.45 40.64 0)
			(effects
				(font
					(size 1.27 1.27)
					(thickness 0.15)
				)
				(justify left bottom)
				(hide yes)
			)
		)
		(property "Description" "SMD Chip Resistor, 100 kohm, ± 1%, 62.5 mW, 0402 [1005 Metric], Thick Film, General Purpose"
			(at 316.23 60.96 0)
			(effects
				(font
					(size 1.27 1.27)
				)
				(hide yes)
			)
		)
		(property "Manufacturer" "Bourns"
			(at 293.37 40.64 0)
			(effects
				(font
					(size 1.27 1.27)
					(thickness 0.15)
				)
				(justify left bottom)
				(hide yes)
			)
		)
		(property "MPN" "CR0402-FX-1003GLF"
			(at 295.91 40.64 0)
			(effects
				(font
					(size 1.27 1.27)
					(thickness 0.15)
				)
				(justify left bottom)
				(hide yes)
			)
		)
		(property "Val" "100k"
			(at 318.77 59.6899 90)
			(effects
				(font
					(size 1.27 1.27)
					(thickness 0.15)
				)
				(justify left)
			)
		)
		(property "License" "Apache-2.0"
			(at 290.83 40.64 0)
			(effects
				(font
					(size 1.27 1.27)
					(thickness 0.15)
				)
				(justify left bottom)
				(hide yes)
			)
		)
		(property "Author" "Antmicro"
			(at 288.29 40.64 0)
			(effects
				(font
					(size 1.27 1.27)
					(thickness 0.15)
				)
				(justify left bottom)
				(hide yes)
			)
		)
		(property "Tolerance" "1%"
			(at 306.07 40.64 0)
			(effects
				(font
					(size 1.27 1.27)
				)
				(justify left bottom)
				(hide yes)
			)
		)
		(property "Public" "False"
			(at 285.75 40.64 0)
			(effects
				(font
					(size 1.27 1.27)
				)
				(justify left bottom)
				(hide yes)
			)
		)
		(pin "1"
		)
		(pin "2"
		)
		(instances
			(project "environment-sensor"
				(path ""
					(reference "R34")
					(unit 1)
				)
			)
		)
	)
	(symbol
		(lib_id "antmicroBatteryHoldersClipsContacts:BAT-HLD-012-SMT-TR")
		(at 231.14 139.7 270)
		(mirror x)
		(unit 1)
		(exclude_from_sim no)
		(in_bom yes)
		(on_board yes)
		(dnp no)
		(fields_autoplaced yes)
		(property "Reference" "BAT1"
			(at 224.79 135.89 90)
			(effects
				(font
					(size 1.524 1.524)
				)
			)
		)
		(property "Value" "BAT-HLD-012-SMT-TR"
			(at 215.9 143.51 90)
			(effects
				(font
					(size 1.524 1.524)
				)
			)
		)
		(property "Footprint" "antmicro-footprints:BAT_BAT-HLD-012-SMT-TR"
			(at 229.87 127 0)
			(effects
				(font
					(size 1.524 1.524)
				)
				(justify left)
				(hide yes)
			)
		)
		(property "Datasheet" "https://www.snapeda.com/parts/BAT-HLD-012-SMT-TR/Linx/datasheet/"
			(at 229.87 124.46 0)
			(effects
				(font
					(size 1.524 1.524)
				)
				(justify left)
				(hide yes)
			)
		)
		(property "Description" "BATTERY HOLDER, CR1216/1225, SMT"
			(at 231.14 139.7 0)
			(effects
				(font
					(size 1.27 1.27)
				)
				(hide yes)
			)
		)
		(property "MPN" "BAT-HLD-012-SMT-TR"
			(at 256.54 143.51 0)
			(effects
				(font
					(size 1.524 1.524)
				)
				(justify left)
				(hide yes)
			)
		)
		(property "Manufacturer" "Linx Technologies"
			(at 234.95 143.51 0)
			(effects
				(font
					(size 1.524 1.524)
				)
				(justify left)
				(hide yes)
			)
		)
		(property "License" "Apache-2.0"
			(at 229.87 121.92 0)
			(effects
				(font
					(size 1.27 1.27)
				)
				(justify left)
				(hide yes)
			)
		)
		(property "Author" "Antmicro"
			(at 248.92 115.57 0)
			(effects
				(font
					(size 1.27 1.27)
					(thickness 0.15)
				)
				(justify left bottom)
				(hide yes)
			)
		)
		(pin "N"
		)
		(pin "P1"
		)
		(pin "P2"
		)
		(instances
			(project "environment-sensor"
				(path ""
					(reference "BAT1")
					(unit 1)
				)
			)
		)
	)
	(symbol
		(lib_id "antmicroTestPoints:TP_1mm_SMD")
		(at 311.15 146.05 0)
		(unit 1)
		(exclude_from_sim no)
		(in_bom yes)
		(on_board yes)
		(dnp no)
		(fields_autoplaced yes)
		(property "Reference" "TP8"
			(at 316.23 146.0499 0)
			(effects
				(font
					(size 1.27 1.27)
					(thickness 0.15)
				)
				(justify left)
			)
		)
		(property "Value" "TP_1mm_SMD"
			(at 316.23 147.3199 0)
			(effects
				(font
					(size 1.27 1.27)
					(thickness 0.15)
				)
				(justify left)
				(hide yes)
			)
		)
		(property "Footprint" "antmicro-footprints:TP_SMD_1mm"
			(at 326.39 156.21 0)
			(effects
				(font
					(size 1.27 1.27)
					(thickness 0.15)
				)
				(justify left bottom)
				(hide yes)
			)
		)
		(property "Datasheet" ""
			(at 326.39 158.75 0)
			(effects
				(font
					(size 1.27 1.27)
					(thickness 0.15)
				)
				(justify left bottom)
				(hide yes)
			)
		)
		(property "Description" "Test point 1mm SMD"
			(at 311.15 146.05 0)
			(effects
				(font
					(size 1.27 1.27)
				)
				(hide yes)
			)
		)
		(property "Author" "Antmicro"
			(at 326.39 161.29 0)
			(effects
				(font
					(size 1.27 1.27)
					(thickness 0.15)
				)
				(justify left bottom)
				(hide yes)
			)
		)
		(property "License" "Apache-2.0"
			(at 326.39 163.83 0)
			(effects
				(font
					(size 1.27 1.27)
					(thickness 0.15)
				)
				(justify left bottom)
				(hide yes)
			)
		)
		(property "MPN" ""
			(at 311.15 146.05 0)
			(effects
				(font
					(size 1.27 1.27)
				)
				(hide yes)
			)
		)
		(property "Manufacturer" ""
			(at 311.15 146.05 0)
			(effects
				(font
					(size 1.27 1.27)
				)
				(hide yes)
			)
		)
		(property "Public" "False"
			(at 326.39 166.37 0)
			(effects
				(font
					(size 1.27 1.27)
				)
				(justify left bottom)
				(hide yes)
			)
		)
		(pin "1"
		)
		(instances
			(project "environment-sensor"
				(path ""
					(reference "TP8")
					(unit 1)
				)
			)
		)
	)
	(symbol
		(lib_id "antmicropower:+3V3")
		(at 306.07 30.48 0)
		(mirror y)
		(unit 1)
		(exclude_from_sim no)
		(in_bom yes)
		(on_board yes)
		(dnp no)
		(fields_autoplaced yes)
		(property "Reference" "#PWR056"
			(at 306.07 34.29 0)
			(effects
				(font
					(size 1.27 1.27)
				)
				(hide yes)
			)
		)
		(property "Value" "+3V3"
			(at 306.07 25.4 0)
			(effects
				(font
					(size 1.27 1.27)
				)
			)
		)
		(property "Footprint" ""
			(at 306.07 30.48 0)
			(effects
				(font
					(size 1.27 1.27)
				)
				(hide yes)
			)
		)
		(property "Datasheet" ""
			(at 306.07 30.48 0)
			(effects
				(font
					(size 1.27 1.27)
				)
				(hide yes)
			)
		)
		(property "Description" ""
			(at 306.07 30.48 0)
			(effects
				(font
					(size 1.27 1.27)
				)
				(hide yes)
			)
		)
		(property "Author" "Antmicro"
			(at 290.83 33.02 0)
			(effects
				(font
					(size 1.27 1.27)
					(thickness 0.15)
				)
				(justify left bottom)
				(hide yes)
			)
		)
		(property "License" "Apache-2.0"
			(at 290.83 35.56 0)
			(effects
				(font
					(size 1.27 1.27)
					(thickness 0.15)
				)
				(justify left bottom)
				(hide yes)
			)
		)
		(pin "1"
		)
		(instances
			(project "environment-sensor"
				(path ""
					(reference "#PWR056")
					(unit 1)
				)
			)
		)
	)
	(symbol
		(lib_id "antmicroResistors0402:R_0R_0402")
		(at 135.89 180.34 0)
		(unit 1)
		(exclude_from_sim no)
		(in_bom yes)
		(on_board yes)
		(dnp no)
		(fields_autoplaced yes)
		(property "Reference" "R13"
			(at 135.89 177.8 0)
			(effects
				(font
					(size 1.27 1.27)
					(thickness 0.15)
				)
			)
		)
		(property "Value" "R_0R_0402"
			(at 156.21 193.04 0)
			(effects
				(font
					(size 1.27 1.27)
					(thickness 0.15)
				)
				(justify left bottom)
				(hide yes)
			)
		)
		(property "Footprint" "antmicro-footprints:R_0402_1005Metric"
			(at 156.21 195.58 0)
			(effects
				(font
					(size 1.27 1.27)
					(thickness 0.15)
				)
				(justify left bottom)
				(hide yes)
			)
		)
		(property "Datasheet" "https://industrial.panasonic.com/cdbs/www-data/pdf/RDA0000/AOA0000C301.pdf"
			(at 156.21 198.12 0)
			(effects
				(font
					(size 1.27 1.27)
					(thickness 0.15)
				)
				(justify left bottom)
				(hide yes)
			)
		)
		(property "Description" "SMD Chip Resistor, Jumper, 0 ohm, 100 mW, 0402 [1005 Metric], Thick Film, General Purpose"
			(at 135.89 180.34 0)
			(effects
				(font
					(size 1.27 1.27)
				)
				(hide yes)
			)
		)
		(property "Manufacturer" "Panasonic"
			(at 156.21 203.2 0)
			(effects
				(font
					(size 1.27 1.27)
					(thickness 0.15)
				)
				(justify left bottom)
				(hide yes)
			)
		)
		(property "MPN" "ERJ2GE0R00X"
			(at 156.21 200.66 0)
			(effects
				(font
					(size 1.27 1.27)
					(thickness 0.15)
				)
				(justify left bottom)
				(hide yes)
			)
		)
		(property "Val" "0R"
			(at 139.7 177.8 0)
			(effects
				(font
					(size 1.27 1.27)
					(thickness 0.15)
				)
			)
		)
		(property "License" "Apache-2.0"
			(at 156.21 205.74 0)
			(effects
				(font
					(size 1.27 1.27)
					(thickness 0.15)
				)
				(justify left bottom)
				(hide yes)
			)
		)
		(property "Author" "Antmicro"
			(at 156.21 208.28 0)
			(effects
				(font
					(size 1.27 1.27)
					(thickness 0.15)
				)
				(justify left bottom)
				(hide yes)
			)
		)
		(property "Tolerance" "~"
			(at 156.21 190.5 0)
			(effects
				(font
					(size 1.27 1.27)
				)
				(justify left bottom)
				(hide yes)
			)
		)
		(property "Current" "1A"
			(at 138.43 180.34 0)
			(effects
				(font
					(size 1.27 1.27)
					(thickness 0.15)
				)
				(hide yes)
			)
		)
		(property "Public" "False"
			(at 156.21 210.82 0)
			(effects
				(font
					(size 1.27 1.27)
				)
				(justify left bottom)
				(hide yes)
			)
		)
		(pin "1"
		)
		(pin "2"
		)
		(instances
			(project "environment-sensor"
				(path ""
					(reference "R13")
					(unit 1)
				)
			)
		)
	)
	(symbol
		(lib_id "antmicropower:GND")
		(at 306.07 153.67 0)
		(mirror y)
		(unit 1)
		(exclude_from_sim no)
		(in_bom yes)
		(on_board yes)
		(dnp no)
		(fields_autoplaced yes)
		(property "Reference" "#PWR055"
			(at 306.07 160.02 0)
			(effects
				(font
					(size 1.27 1.27)
				)
				(hide yes)
			)
		)
		(property "Value" "GND"
			(at 304.8 157.48 0)
			(effects
				(font
					(size 1.27 1.27)
				)
				(justify left)
			)
		)
		(property "Footprint" ""
			(at 306.07 153.67 0)
			(effects
				(font
					(size 1.27 1.27)
				)
				(hide yes)
			)
		)
		(property "Datasheet" ""
			(at 306.07 153.67 0)
			(effects
				(font
					(size 1.27 1.27)
				)
				(hide yes)
			)
		)
		(property "Description" ""
			(at 306.07 153.67 0)
			(effects
				(font
					(size 1.27 1.27)
				)
				(hide yes)
			)
		)
		(property "Author" "Antmicro"
			(at 297.18 161.29 0)
			(effects
				(font
					(size 1.27 1.27)
					(thickness 0.15)
				)
				(justify left bottom)
				(hide yes)
			)
		)
		(property "License" "Apache-2.0"
			(at 297.18 163.83 0)
			(effects
				(font
					(size 1.27 1.27)
					(thickness 0.15)
				)
				(justify left bottom)
				(hide yes)
			)
		)
		(pin "1"
		)
		(instances
			(project "environment-sensor"
				(path ""
					(reference "#PWR055")
					(unit 1)
				)
			)
		)
	)
	(symbol
		(lib_id "antmicropower:GND")
		(at 204.47 119.38 0)
		(mirror y)
		(unit 1)
		(exclude_from_sim no)
		(in_bom yes)
		(on_board yes)
		(dnp no)
		(fields_autoplaced yes)
		(property "Reference" "#PWR051"
			(at 204.47 125.73 0)
			(effects
				(font
					(size 1.27 1.27)
				)
				(hide yes)
			)
		)
		(property "Value" "GND"
			(at 204.47 124.46 0)
			(effects
				(font
					(size 1.27 1.27)
				)
			)
		)
		(property "Footprint" ""
			(at 204.47 119.38 0)
			(effects
				(font
					(size 1.27 1.27)
				)
				(hide yes)
			)
		)
		(property "Datasheet" ""
			(at 204.47 119.38 0)
			(effects
				(font
					(size 1.27 1.27)
				)
				(hide yes)
			)
		)
		(property "Description" ""
			(at 204.47 119.38 0)
			(effects
				(font
					(size 1.27 1.27)
				)
				(hide yes)
			)
		)
		(property "Author" "Antmicro"
			(at 195.58 127 0)
			(effects
				(font
					(size 1.27 1.27)
					(thickness 0.15)
				)
				(justify left bottom)
				(hide yes)
			)
		)
		(property "License" "Apache-2.0"
			(at 195.58 129.54 0)
			(effects
				(font
					(size 1.27 1.27)
					(thickness 0.15)
				)
				(justify left bottom)
				(hide yes)
			)
		)
		(pin "1"
		)
		(instances
			(project "environment-sensor"
				(path ""
					(reference "#PWR051")
					(unit 1)
				)
			)
		)
	)
	(symbol
		(lib_id "antmicropower:GND")
		(at 63.5 76.2 0)
		(unit 1)
		(exclude_from_sim no)
		(in_bom yes)
		(on_board yes)
		(dnp no)
		(fields_autoplaced yes)
		(property "Reference" "#PWR08"
			(at 63.5 82.55 0)
			(effects
				(font
					(size 1.27 1.27)
				)
				(hide yes)
			)
		)
		(property "Value" "GND"
			(at 63.5 81.28 0)
			(effects
				(font
					(size 1.27 1.27)
				)
			)
		)
		(property "Footprint" ""
			(at 63.5 76.2 0)
			(effects
				(font
					(size 1.27 1.27)
				)
				(hide yes)
			)
		)
		(property "Datasheet" ""
			(at 63.5 76.2 0)
			(effects
				(font
					(size 1.27 1.27)
				)
				(hide yes)
			)
		)
		(property "Description" ""
			(at 63.5 76.2 0)
			(effects
				(font
					(size 1.27 1.27)
				)
				(hide yes)
			)
		)
		(property "Author" "Antmicro"
			(at 72.39 83.82 0)
			(effects
				(font
					(size 1.27 1.27)
					(thickness 0.15)
				)
				(justify left bottom)
				(hide yes)
			)
		)
		(property "License" "Apache-2.0"
			(at 72.39 86.36 0)
			(effects
				(font
					(size 1.27 1.27)
					(thickness 0.15)
				)
				(justify left bottom)
				(hide yes)
			)
		)
		(pin "1"
		)
		(instances
			(project "environment-sensor"
				(path ""
					(reference "#PWR08")
					(unit 1)
				)
			)
		)
	)
	(symbol
		(lib_id "antmicroMicrocontrollers:STM32G474CET6")
		(at 241.3 132.08 0)
		(unit 1)
		(exclude_from_sim no)
		(in_bom yes)
		(on_board yes)
		(dnp no)
		(fields_autoplaced yes)
		(property "Reference" "U3"
			(at 257.81 195.58 0)
			(effects
				(font
					(size 1.27 1.27)
					(thickness 0.15)
				)
			)
		)
		(property "Value" "STM32G474CET6"
			(at 257.81 198.12 0)
			(effects
				(font
					(size 1.27 1.27)
					(thickness 0.15)
				)
			)
		)
		(property "Footprint" "antmicro-footprints:LQFP-48_7x7mm_P0.5mm"
			(at 299.72 142.24 0)
			(effects
				(font
					(size 1.27 1.27)
					(thickness 0.15)
				)
				(justify left bottom)
				(hide yes)
			)
		)
		(property "Datasheet" "https://www.st.com/resource/en/datasheet/stm32g474ce.pdf"
			(at 299.72 144.78 0)
			(effects
				(font
					(size 1.27 1.27)
					(thickness 0.15)
				)
				(justify left bottom)
				(hide yes)
			)
		)
		(property "Description" "ARM MCU, STM32 Family STM32G4 Series Microcontrollers, ARM Cortex-M4F, 32 bit, 170 MHz, 512 KB"
			(at 241.3 132.08 0)
			(effects
				(font
					(size 1.27 1.27)
				)
				(hide yes)
			)
		)
		(property "MPN" "STM32G474CET6"
			(at 299.72 147.32 0)
			(effects
				(font
					(size 1.27 1.27)
					(thickness 0.15)
				)
				(justify left bottom)
				(hide yes)
			)
		)
		(property "Manufacturer" "STMicroelectronics"
			(at 299.72 149.86 0)
			(effects
				(font
					(size 1.27 1.27)
					(thickness 0.15)
				)
				(justify left bottom)
				(hide yes)
			)
		)
		(property "License" "Apache-2.0"
			(at 299.72 152.4 0)
			(effects
				(font
					(size 1.27 1.27)
					(thickness 0.15)
				)
				(justify left bottom)
				(hide yes)
			)
		)
		(property "Author" "Antmicro"
			(at 299.72 154.94 0)
			(effects
				(font
					(size 1.27 1.27)
					(thickness 0.15)
				)
				(justify left bottom)
				(hide yes)
			)
		)
		(pin "18"
		)
		(pin "6"
		)
		(pin "42"
		)
		(pin "47"
		)
		(pin "44"
		)
		(pin "24"
		)
		(pin "8"
		)
		(pin "46"
		)
		(pin "25"
		)
		(pin "34"
		)
		(pin "33"
		)
		(pin "35"
		)
		(pin "32"
		)
		(pin "31"
		)
		(pin "48"
		)
		(pin "45"
		)
		(pin "43"
		)
		(pin "5"
		)
		(pin "9"
		)
		(pin "7"
		)
		(pin "17"
		)
		(pin "27"
		)
		(pin "14"
		)
		(pin "13"
		)
		(pin "15"
		)
		(pin "36"
		)
		(pin "10"
		)
		(pin "16"
		)
		(pin "19"
		)
		(pin "26"
		)
		(pin "22"
		)
		(pin "41"
		)
		(pin "20"
		)
		(pin "40"
		)
		(pin "37"
		)
		(pin "38"
		)
		(pin "23"
		)
		(pin "1"
		)
		(pin "21"
		)
		(pin "11"
		)
		(pin "4"
		)
		(pin "30"
		)
		(pin "3"
		)
		(pin "12"
		)
		(pin "2"
		)
		(pin "28"
		)
		(pin "29"
		)
		(pin "39"
		)
		(instances
			(project "environment-sensor"
				(path ""
					(reference "U3")
					(unit 1)
				)
			)
		)
	)
	(symbol
		(lib_id "antmicroFerriteBeadsandChips:FB_120Z_2A_Murata-BLM18PG_0603")
		(at 100.33 46.99 0)
		(unit 1)
		(exclude_from_sim no)
		(in_bom yes)
		(on_board yes)
		(dnp no)
		(fields_autoplaced yes)
		(property "Reference" "FB2"
			(at 102.8319 40.64 0)
			(effects
				(font
					(size 1.27 1.27)
					(thickness 0.15)
				)
			)
		)
		(property "Value" "FB_120Z_2A_Murata-BLM18PG_0603"
			(at 115.57 49.53 0)
			(effects
				(font
					(size 1.27 1.27)
					(thickness 0.15)
				)
				(justify left bottom)
				(hide yes)
			)
		)
		(property "Footprint" "antmicro-footprints:FB_0603_1608Metric"
			(at 115.57 54.61 0)
			(effects
				(font
					(size 1.27 1.27)
					(thickness 0.15)
				)
				(justify left bottom)
				(hide yes)
			)
		)
		(property "Datasheet" "https://www.murata.com/en-us/products/productdata/8796738650142/ENFA0003.pdf"
			(at 115.57 57.15 0)
			(effects
				(font
					(size 1.27 1.27)
					(thickness 0.15)
				)
				(justify left bottom)
				(hide yes)
			)
		)
		(property "Description" "Ferrite Bead, 0603 [1608 Metric], 120 ohm, 2 A, BLM18P, 0.05 ohm, ± 25%, DC power line"
			(at 100.33 46.99 0)
			(effects
				(font
					(size 1.27 1.27)
				)
				(hide yes)
			)
		)
		(property "Val" "120Z/2A"
			(at 102.8319 43.18 0)
			(effects
				(font
					(size 1.27 1.27)
				)
			)
		)
		(property "MPN" "BLM18PG121SN1D"
			(at 115.57 59.69 0)
			(effects
				(font
					(size 1.27 1.27)
					(thickness 0.15)
				)
				(justify left bottom)
				(hide yes)
			)
		)
		(property "Manufacturer" "Murata"
			(at 115.57 62.23 0)
			(effects
				(font
					(size 1.27 1.27)
					(thickness 0.15)
				)
				(justify left bottom)
				(hide yes)
			)
		)
		(property "Current" ""
			(at 120.65 69.85 0)
			(effects
				(font
					(size 1.27 1.27)
					(thickness 0.15)
				)
				(justify left bottom)
				(hide yes)
			)
		)
		(property "Author" "Antmicro"
			(at 115.57 64.77 0)
			(effects
				(font
					(size 1.27 1.27)
					(thickness 0.15)
				)
				(justify left bottom)
				(hide yes)
			)
		)
		(property "License" "Apache-2.0"
			(at 115.57 67.31 0)
			(effects
				(font
					(size 1.27 1.27)
					(thickness 0.15)
				)
				(justify left bottom)
				(hide yes)
			)
		)
		(property "Public" "False"
			(at 120.65 62.23 0)
			(effects
				(font
					(size 1.27 1.27)
				)
				(justify left bottom)
				(hide yes)
			)
		)
		(pin "2"
		)
		(pin "1"
		)
		(instances
			(project "environment-sensor"
				(path ""
					(reference "FB2")
					(unit 1)
				)
			)
		)
	)
	(symbol
		(lib_id "antmicroTestPoints:TP_1mm_SMD")
		(at 293.37 71.12 0)
		(unit 1)
		(exclude_from_sim no)
		(in_bom yes)
		(on_board yes)
		(dnp no)
		(fields_autoplaced yes)
		(property "Reference" "TP7"
			(at 296.545 74.93 0)
			(effects
				(font
					(size 1.27 1.27)
					(thickness 0.15)
				)
			)
		)
		(property "Value" "TP_1mm_SMD"
			(at 296.545 77.47 0)
			(effects
				(font
					(size 1.27 1.27)
					(thickness 0.15)
				)
				(hide yes)
			)
		)
		(property "Footprint" "antmicro-footprints:TP_SMD_1mm"
			(at 308.61 81.28 0)
			(effects
				(font
					(size 1.27 1.27)
					(thickness 0.15)
				)
				(justify left bottom)
				(hide yes)
			)
		)
		(property "Datasheet" ""
			(at 308.61 83.82 0)
			(effects
				(font
					(size 1.27 1.27)
					(thickness 0.15)
				)
				(justify left bottom)
				(hide yes)
			)
		)
		(property "Description" "Test point 1mm SMD"
			(at 293.37 71.12 0)
			(effects
				(font
					(size 1.27 1.27)
				)
				(hide yes)
			)
		)
		(property "Author" "Antmicro"
			(at 308.61 86.36 0)
			(effects
				(font
					(size 1.27 1.27)
					(thickness 0.15)
				)
				(justify left bottom)
				(hide yes)
			)
		)
		(property "License" "Apache-2.0"
			(at 308.61 88.9 0)
			(effects
				(font
					(size 1.27 1.27)
					(thickness 0.15)
				)
				(justify left bottom)
				(hide yes)
			)
		)
		(property "MPN" ""
			(at 293.37 71.12 0)
			(effects
				(font
					(size 1.27 1.27)
				)
				(hide yes)
			)
		)
		(property "Manufacturer" ""
			(at 293.37 71.12 0)
			(effects
				(font
					(size 1.27 1.27)
				)
				(hide yes)
			)
		)
		(property "Public" "False"
			(at 308.61 91.44 0)
			(effects
				(font
					(size 1.27 1.27)
				)
				(justify left bottom)
				(hide yes)
			)
		)
		(pin "1"
		)
		(instances
			(project "environment-sensor"
				(path ""
					(reference "TP7")
					(unit 1)
				)
			)
		)
	)
	(symbol
		(lib_id "antmicropower:GND")
		(at 215.9 139.7 270)
		(mirror x)
		(unit 1)
		(exclude_from_sim no)
		(in_bom yes)
		(on_board yes)
		(dnp no)
		(fields_autoplaced yes)
		(property "Reference" "#PWR053"
			(at 209.55 139.7 0)
			(effects
				(font
					(size 1.27 1.27)
				)
				(hide yes)
			)
		)
		(property "Value" "GND"
			(at 212.09 139.6999 90)
			(effects
				(font
					(size 1.27 1.27)
				)
				(justify right)
			)
		)
		(property "Footprint" ""
			(at 215.9 139.7 0)
			(effects
				(font
					(size 1.27 1.27)
				)
				(hide yes)
			)
		)
		(property "Datasheet" ""
			(at 215.9 139.7 0)
			(effects
				(font
					(size 1.27 1.27)
				)
				(hide yes)
			)
		)
		(property "Description" ""
			(at 215.9 139.7 0)
			(effects
				(font
					(size 1.27 1.27)
				)
				(hide yes)
			)
		)
		(property "Author" "Antmicro"
			(at 208.28 130.81 0)
			(effects
				(font
					(size 1.27 1.27)
					(thickness 0.15)
				)
				(justify left bottom)
				(hide yes)
			)
		)
		(property "License" "Apache-2.0"
			(at 205.74 130.81 0)
			(effects
				(font
					(size 1.27 1.27)
					(thickness 0.15)
				)
				(justify left bottom)
				(hide yes)
			)
		)
		(pin "1"
		)
		(instances
			(project "environment-sensor"
				(path ""
					(reference "#PWR053")
					(unit 1)
				)
			)
		)
	)
	(symbol
		(lib_id "antmicroCapacitors0402:C_10p_0402")
		(at 299.72 212.09 270)
		(mirror x)
		(unit 1)
		(exclude_from_sim no)
		(in_bom yes)
		(on_board yes)
		(dnp no)
		(fields_autoplaced yes)
		(property "Reference" "C23"
			(at 302.26 208.2735 90)
			(effects
				(font
					(size 1.27 1.27)
					(thickness 0.15)
				)
				(justify left)
			)
		)
		(property "Value" "C_10p_0402"
			(at 289.56 191.77 0)
			(effects
				(font
					(size 1.27 1.27)
					(thickness 0.15)
				)
				(justify left bottom)
				(hide yes)
			)
		)
		(property "Footprint" "antmicro-footprints:C_0402_1005Metric"
			(at 287.02 191.77 0)
			(effects
				(font
					(size 1.27 1.27)
					(thickness 0.15)
				)
				(justify left bottom)
				(hide yes)
			)
		)
		(property "Datasheet" "https://www.murata.com/products/productdetail?partno=GCM1555C1H100GA16%23"
			(at 284.48 191.77 0)
			(effects
				(font
					(size 1.27 1.27)
					(thickness 0.15)
				)
				(justify left bottom)
				(hide yes)
			)
		)
		(property "Description" "SMD Multilayer Ceramic Capacitor, 10 pF, 50 V, 0402 [1005 Metric], ± 2%, C0G / NP0, GCM"
			(at 299.72 212.09 0)
			(effects
				(font
					(size 1.27 1.27)
				)
				(hide yes)
			)
		)
		(property "Manufacturer" "Murata"
			(at 279.4 191.77 0)
			(effects
				(font
					(size 1.27 1.27)
					(thickness 0.15)
				)
				(justify left bottom)
				(hide yes)
			)
		)
		(property "MPN" "GCM1555C1H100GA16D"
			(at 281.94 191.77 0)
			(effects
				(font
					(size 1.27 1.27)
					(thickness 0.15)
				)
				(justify left bottom)
				(hide yes)
			)
		)
		(property "Val" "10p"
			(at 302.26 210.8135 90)
			(effects
				(font
					(size 1.27 1.27)
					(thickness 0.15)
				)
				(justify left)
			)
		)
		(property "License" "Apache-2.0"
			(at 276.86 191.77 0)
			(effects
				(font
					(size 1.27 1.27)
					(thickness 0.15)
				)
				(justify left bottom)
				(hide yes)
			)
		)
		(property "Author" "Antmicro"
			(at 274.32 191.77 0)
			(effects
				(font
					(size 1.27 1.27)
					(thickness 0.15)
				)
				(justify left bottom)
				(hide yes)
			)
		)
		(property "Voltage" "50V"
			(at 271.78 191.77 0)
			(effects
				(font
					(size 1.27 1.27)
				)
				(justify left bottom)
				(hide yes)
			)
		)
		(property "Dielectric" "C0G"
			(at 269.24 191.77 0)
			(effects
				(font
					(size 1.27 1.27)
				)
				(justify left bottom)
				(hide yes)
			)
		)
		(property "Public" "False"
			(at 266.7 191.77 0)
			(effects
				(font
					(size 1.27 1.27)
				)
				(justify left bottom)
				(hide yes)
			)
		)
		(pin "1"
		)
		(pin "2"
		)
		(instances
			(project "environment-sensor"
				(path ""
					(reference "C23")
					(unit 1)
				)
			)
		)
	)
	(symbol
		(lib_id "antmicropower:GND")
		(at 260.35 40.64 0)
		(unit 1)
		(exclude_from_sim no)
		(in_bom yes)
		(on_board yes)
		(dnp no)
		(fields_autoplaced yes)
		(property "Reference" "#PWR041"
			(at 260.35 46.99 0)
			(effects
				(font
					(size 1.27 1.27)
				)
				(hide yes)
			)
		)
		(property "Value" "GND"
			(at 260.35 45.72 0)
			(effects
				(font
					(size 1.27 1.27)
				)
			)
		)
		(property "Footprint" ""
			(at 260.35 40.64 0)
			(effects
				(font
					(size 1.27 1.27)
				)
				(hide yes)
			)
		)
		(property "Datasheet" ""
			(at 260.35 40.64 0)
			(effects
				(font
					(size 1.27 1.27)
				)
				(hide yes)
			)
		)
		(property "Description" ""
			(at 260.35 40.64 0)
			(effects
				(font
					(size 1.27 1.27)
				)
				(hide yes)
			)
		)
		(property "Author" "Antmicro"
			(at 269.24 48.26 0)
			(effects
				(font
					(size 1.27 1.27)
					(thickness 0.15)
				)
				(justify left bottom)
				(hide yes)
			)
		)
		(property "License" "Apache-2.0"
			(at 269.24 50.8 0)
			(effects
				(font
					(size 1.27 1.27)
					(thickness 0.15)
				)
				(justify left bottom)
				(hide yes)
			)
		)
		(pin "1"
		)
		(instances
			(project "environment-sensor"
				(path ""
					(reference "#PWR041")
					(unit 1)
				)
			)
		)
	)
	(symbol
		(lib_id "antmicropower:GND")
		(at 300.99 118.11 0)
		(mirror y)
		(unit 1)
		(exclude_from_sim no)
		(in_bom yes)
		(on_board yes)
		(dnp no)
		(fields_autoplaced yes)
		(property "Reference" "#PWR023"
			(at 300.99 124.46 0)
			(effects
				(font
					(size 1.27 1.27)
				)
				(hide yes)
			)
		)
		(property "Value" "GND"
			(at 300.99 123.19 0)
			(effects
				(font
					(size 1.27 1.27)
				)
			)
		)
		(property "Footprint" ""
			(at 300.99 118.11 0)
			(effects
				(font
					(size 1.27 1.27)
				)
				(hide yes)
			)
		)
		(property "Datasheet" ""
			(at 300.99 118.11 0)
			(effects
				(font
					(size 1.27 1.27)
				)
				(hide yes)
			)
		)
		(property "Description" ""
			(at 300.99 118.11 0)
			(effects
				(font
					(size 1.27 1.27)
				)
				(hide yes)
			)
		)
		(property "Author" "Antmicro"
			(at 292.1 125.73 0)
			(effects
				(font
					(size 1.27 1.27)
					(thickness 0.15)
				)
				(justify left bottom)
				(hide yes)
			)
		)
		(property "License" "Apache-2.0"
			(at 292.1 128.27 0)
			(effects
				(font
					(size 1.27 1.27)
					(thickness 0.15)
				)
				(justify left bottom)
				(hide yes)
			)
		)
		(pin "1"
		)
		(instances
			(project "environment-sensor"
				(path ""
					(reference "#PWR023")
					(unit 1)
				)
			)
		)
	)
	(symbol
		(lib_id "antmicropower:GND")
		(at 387.35 161.29 0)
		(mirror y)
		(unit 1)
		(exclude_from_sim no)
		(in_bom yes)
		(on_board yes)
		(dnp no)
		(fields_autoplaced yes)
		(property "Reference" "#PWR076"
			(at 387.35 167.64 0)
			(effects
				(font
					(size 1.27 1.27)
				)
				(hide yes)
			)
		)
		(property "Value" "GND"
			(at 389.89 162.5599 0)
			(effects
				(font
					(size 1.27 1.27)
				)
				(justify right)
			)
		)
		(property "Footprint" ""
			(at 387.35 161.29 0)
			(effects
				(font
					(size 1.27 1.27)
				)
				(hide yes)
			)
		)
		(property "Datasheet" ""
			(at 387.35 161.29 0)
			(effects
				(font
					(size 1.27 1.27)
				)
				(hide yes)
			)
		)
		(property "Description" ""
			(at 387.35 161.29 0)
			(effects
				(font
					(size 1.27 1.27)
				)
				(hide yes)
			)
		)
		(property "Author" "Antmicro"
			(at 378.46 168.91 0)
			(effects
				(font
					(size 1.27 1.27)
					(thickness 0.15)
				)
				(justify left bottom)
				(hide yes)
			)
		)
		(property "License" "Apache-2.0"
			(at 378.46 171.45 0)
			(effects
				(font
					(size 1.27 1.27)
					(thickness 0.15)
				)
				(justify left bottom)
				(hide yes)
			)
		)
		(pin "1"
		)
		(instances
			(project "environment-sensor"
				(path ""
					(reference "#PWR076")
					(unit 1)
				)
			)
		)
	)
	(symbol
		(lib_id "antmicropower:GND")
		(at 199.39 59.69 0)
		(unit 1)
		(exclude_from_sim no)
		(in_bom yes)
		(on_board yes)
		(dnp no)
		(fields_autoplaced yes)
		(property "Reference" "#PWR026"
			(at 199.39 66.04 0)
			(effects
				(font
					(size 1.27 1.27)
				)
				(hide yes)
			)
		)
		(property "Value" "GND"
			(at 199.39 64.77 0)
			(effects
				(font
					(size 1.27 1.27)
				)
			)
		)
		(property "Footprint" ""
			(at 199.39 59.69 0)
			(effects
				(font
					(size 1.27 1.27)
				)
				(hide yes)
			)
		)
		(property "Datasheet" ""
			(at 199.39 59.69 0)
			(effects
				(font
					(size 1.27 1.27)
				)
				(hide yes)
			)
		)
		(property "Description" ""
			(at 199.39 59.69 0)
			(effects
				(font
					(size 1.27 1.27)
				)
				(hide yes)
			)
		)
		(property "Author" "Antmicro"
			(at 208.28 67.31 0)
			(effects
				(font
					(size 1.27 1.27)
					(thickness 0.15)
				)
				(justify left bottom)
				(hide yes)
			)
		)
		(property "License" "Apache-2.0"
			(at 208.28 69.85 0)
			(effects
				(font
					(size 1.27 1.27)
					(thickness 0.15)
				)
				(justify left bottom)
				(hide yes)
			)
		)
		(pin "1"
		)
		(instances
			(project "environment-sensor"
				(path ""
					(reference "#PWR026")
					(unit 1)
				)
			)
		)
	)
	(symbol
		(lib_id "antmicroResistors0402:R_0R_0402")
		(at 232.41 184.15 0)
		(unit 1)
		(exclude_from_sim no)
		(in_bom yes)
		(on_board yes)
		(dnp no)
		(fields_autoplaced yes)
		(property "Reference" "R20"
			(at 232.41 180.34 0)
			(effects
				(font
					(size 1.27 1.27)
					(thickness 0.15)
				)
			)
		)
		(property "Value" "R_0R_0402"
			(at 252.73 196.85 0)
			(effects
				(font
					(size 1.27 1.27)
					(thickness 0.15)
				)
				(justify left bottom)
				(hide yes)
			)
		)
		(property "Footprint" "antmicro-footprints:R_0402_1005Metric"
			(at 252.73 199.39 0)
			(effects
				(font
					(size 1.27 1.27)
					(thickness 0.15)
				)
				(justify left bottom)
				(hide yes)
			)
		)
		(property "Datasheet" "https://industrial.panasonic.com/cdbs/www-data/pdf/RDA0000/AOA0000C301.pdf"
			(at 252.73 201.93 0)
			(effects
				(font
					(size 1.27 1.27)
					(thickness 0.15)
				)
				(justify left bottom)
				(hide yes)
			)
		)
		(property "Description" "SMD Chip Resistor, Jumper, 0 ohm, 100 mW, 0402 [1005 Metric], Thick Film, General Purpose"
			(at 232.41 184.15 0)
			(effects
				(font
					(size 1.27 1.27)
				)
				(hide yes)
			)
		)
		(property "Manufacturer" "Panasonic"
			(at 252.73 207.01 0)
			(effects
				(font
					(size 1.27 1.27)
					(thickness 0.15)
				)
				(justify left bottom)
				(hide yes)
			)
		)
		(property "MPN" "ERJ2GE0R00X"
			(at 252.73 204.47 0)
			(effects
				(font
					(size 1.27 1.27)
					(thickness 0.15)
				)
				(justify left bottom)
				(hide yes)
			)
		)
		(property "Val" "0R"
			(at 237.49 180.34 0)
			(effects
				(font
					(size 1.27 1.27)
					(thickness 0.15)
				)
			)
		)
		(property "License" "Apache-2.0"
			(at 252.73 209.55 0)
			(effects
				(font
					(size 1.27 1.27)
					(thickness 0.15)
				)
				(justify left bottom)
				(hide yes)
			)
		)
		(property "Author" "Antmicro"
			(at 252.73 212.09 0)
			(effects
				(font
					(size 1.27 1.27)
					(thickness 0.15)
				)
				(justify left bottom)
				(hide yes)
			)
		)
		(property "Tolerance" "~"
			(at 252.73 194.31 0)
			(effects
				(font
					(size 1.27 1.27)
				)
				(justify left bottom)
				(hide yes)
			)
		)
		(property "Current" "1A"
			(at 234.95 184.15 0)
			(effects
				(font
					(size 1.27 1.27)
					(thickness 0.15)
				)
				(hide yes)
			)
		)
		(property "Public" "False"
			(at 252.73 214.63 0)
			(effects
				(font
					(size 1.27 1.27)
				)
				(justify left bottom)
				(hide yes)
			)
		)
		(pin "1"
		)
		(pin "2"
		)
		(instances
			(project "environment-sensor"
				(path ""
					(reference "R20")
					(unit 1)
				)
			)
		)
	)
	(symbol
		(lib_id "antmicroTVSDiodes:ESD9X5.0ST5G")
		(at 364.49 240.03 90)
		(unit 1)
		(exclude_from_sim no)
		(in_bom yes)
		(on_board yes)
		(dnp no)
		(fields_autoplaced yes)
		(property "Reference" "D9"
			(at 368.3 234.6324 90)
			(effects
				(font
					(size 1.27 1.27)
					(thickness 0.15)
				)
				(justify right)
			)
		)
		(property "Value" "ESD9X5.0ST5G"
			(at 368.3 237.1724 90)
			(effects
				(font
					(size 1.27 1.27)
					(thickness 0.15)
				)
				(justify right)
			)
		)
		(property "Footprint" "antmicro-footprints:SOD-923"
			(at 372.11 218.44 0)
			(effects
				(font
					(size 1.27 1.27)
					(thickness 0.15)
				)
				(justify left bottom)
				(hide yes)
			)
		)
		(property "Datasheet" "https://www.onsemi.com/pdf/datasheet/esd9x3.3st5g-d.pdf"
			(at 374.65 218.44 0)
			(effects
				(font
					(size 1.27 1.27)
					(thickness 0.15)
				)
				(justify left bottom)
				(hide yes)
			)
		)
		(property "Description" "Unidirectional TVS, 30 kV,  SOD-923, 5 V, 65 pF"
			(at 364.49 240.03 0)
			(effects
				(font
					(size 1.27 1.27)
				)
				(hide yes)
			)
		)
		(property "Manufacturer" "ON Semiconductor"
			(at 377.19 218.44 0)
			(effects
				(font
					(size 1.27 1.27)
					(thickness 0.15)
				)
				(justify left bottom)
				(hide yes)
			)
		)
		(property "MPN" "ESD9X5.0ST5G"
			(at 379.73 218.44 0)
			(effects
				(font
					(size 1.27 1.27)
					(thickness 0.15)
				)
				(justify left bottom)
				(hide yes)
			)
		)
		(property "Author" "Antmicro"
			(at 382.27 218.44 0)
			(effects
				(font
					(size 1.27 1.27)
					(thickness 0.15)
				)
				(justify left bottom)
				(hide yes)
			)
		)
		(property "License" "Apache-2.0"
			(at 384.81 218.44 0)
			(effects
				(font
					(size 1.27 1.27)
					(thickness 0.15)
				)
				(justify left bottom)
				(hide yes)
			)
		)
		(property "Public" "False"
			(at 382.27 219.71 0)
			(effects
				(font
					(size 1.27 1.27)
				)
				(justify left bottom)
				(hide yes)
			)
		)
		(pin "1"
		)
		(pin "2"
		)
		(instances
			(project "environment-sensor"
				(path ""
					(reference "D9")
					(unit 1)
				)
			)
		)
	)
	(symbol
		(lib_id "antmicropower:+5V")
		(at 36.83 176.53 0)
		(unit 1)
		(exclude_from_sim no)
		(in_bom yes)
		(on_board yes)
		(dnp no)
		(fields_autoplaced yes)
		(property "Reference" "#PWR02"
			(at 52.07 179.07 0)
			(effects
				(font
					(size 1.27 1.27)
					(thickness 0.15)
				)
				(justify left bottom)
				(hide yes)
			)
		)
		(property "Value" "+5V"
			(at 36.83 171.45 0)
			(effects
				(font
					(size 1.27 1.27)
					(thickness 0.15)
				)
			)
		)
		(property "Footprint" ""
			(at 52.07 184.15 0)
			(effects
				(font
					(size 1.27 1.27)
					(thickness 0.15)
				)
				(justify left bottom)
				(hide yes)
			)
		)
		(property "Datasheet" ""
			(at 52.07 186.69 0)
			(effects
				(font
					(size 1.27 1.27)
					(thickness 0.15)
				)
				(justify left bottom)
				(hide yes)
			)
		)
		(property "Description" ""
			(at 36.83 176.53 0)
			(effects
				(font
					(size 1.27 1.27)
				)
				(hide yes)
			)
		)
		(property "Author" "Antmicro"
			(at 52.07 184.15 0)
			(effects
				(font
					(size 1.27 1.27)
					(thickness 0.15)
				)
				(justify left bottom)
				(hide yes)
			)
		)
		(property "License" "Apache-2.0"
			(at 52.07 186.69 0)
			(effects
				(font
					(size 1.27 1.27)
					(thickness 0.15)
				)
				(justify left bottom)
				(hide yes)
			)
		)
		(pin "1"
		)
		(instances
			(project "environment-sensor"
				(path ""
					(reference "#PWR02")
					(unit 1)
				)
			)
		)
	)
	(symbol
		(lib_id "antmicropower:GND")
		(at 276.86 63.5 0)
		(mirror y)
		(unit 1)
		(exclude_from_sim no)
		(in_bom yes)
		(on_board yes)
		(dnp no)
		(fields_autoplaced yes)
		(property "Reference" "#PWR045"
			(at 276.86 69.85 0)
			(effects
				(font
					(size 1.27 1.27)
				)
				(hide yes)
			)
		)
		(property "Value" "GND"
			(at 276.86 68.58 0)
			(effects
				(font
					(size 1.27 1.27)
				)
			)
		)
		(property "Footprint" ""
			(at 276.86 63.5 0)
			(effects
				(font
					(size 1.27 1.27)
				)
				(hide yes)
			)
		)
		(property "Datasheet" ""
			(at 276.86 63.5 0)
			(effects
				(font
					(size 1.27 1.27)
				)
				(hide yes)
			)
		)
		(property "Description" ""
			(at 276.86 63.5 0)
			(effects
				(font
					(size 1.27 1.27)
				)
				(hide yes)
			)
		)
		(property "Author" "Antmicro"
			(at 267.97 71.12 0)
			(effects
				(font
					(size 1.27 1.27)
					(thickness 0.15)
				)
				(justify left bottom)
				(hide yes)
			)
		)
		(property "License" "Apache-2.0"
			(at 267.97 73.66 0)
			(effects
				(font
					(size 1.27 1.27)
					(thickness 0.15)
				)
				(justify left bottom)
				(hide yes)
			)
		)
		(pin "1"
		)
		(instances
			(project "environment-sensor"
				(path ""
					(reference "#PWR045")
					(unit 1)
				)
			)
		)
	)
	(symbol
		(lib_id "antmicroCapacitors0402:C_100n_0402")
		(at 231.14 113.03 90)
		(mirror x)
		(unit 1)
		(exclude_from_sim no)
		(in_bom yes)
		(on_board yes)
		(dnp no)
		(fields_autoplaced yes)
		(property "Reference" "C19"
			(at 228.6 114.3062 90)
			(effects
				(font
					(size 1.27 1.27)
					(thickness 0.15)
				)
				(justify left)
			)
		)
		(property "Value" "C_100n_0402"
			(at 241.3 133.35 0)
			(effects
				(font
					(size 1.27 1.27)
					(thickness 0.15)
				)
				(justify left bottom)
				(hide yes)
			)
		)
		(property "Footprint" "antmicro-footprints:C_0402_1005Metric"
			(at 243.84 133.35 0)
			(effects
				(font
					(size 1.27 1.27)
					(thickness 0.15)
				)
				(justify left bottom)
				(hide yes)
			)
		)
		(property "Datasheet" "https://www.murata.com/products/productdetail?partno=GRM155R61H104KE14%23"
			(at 246.38 133.35 0)
			(effects
				(font
					(size 1.27 1.27)
					(thickness 0.15)
				)
				(justify left bottom)
				(hide yes)
			)
		)
		(property "Description" "SMD Multilayer Ceramic Capacitor, 0.1 µF, 50 V, 0402 [1005 Metric], ± 10%, X5R, GRM Series"
			(at 231.14 113.03 0)
			(effects
				(font
					(size 1.27 1.27)
				)
				(hide yes)
			)
		)
		(property "Manufacturer" "Murata"
			(at 251.46 133.35 0)
			(effects
				(font
					(size 1.27 1.27)
					(thickness 0.15)
				)
				(justify left bottom)
				(hide yes)
			)
		)
		(property "MPN" "GRM155R61H104KE14D"
			(at 248.92 133.35 0)
			(effects
				(font
					(size 1.27 1.27)
					(thickness 0.15)
				)
				(justify left bottom)
				(hide yes)
			)
		)
		(property "Val" "100n"
			(at 228.6 116.8462 90)
			(effects
				(font
					(size 1.27 1.27)
					(thickness 0.15)
				)
				(justify left)
			)
		)
		(property "License" "Apache-2.0"
			(at 254 133.35 0)
			(effects
				(font
					(size 1.27 1.27)
					(thickness 0.15)
				)
				(justify left bottom)
				(hide yes)
			)
		)
		(property "Author" "Antmicro"
			(at 256.54 133.35 0)
			(effects
				(font
					(size 1.27 1.27)
					(thickness 0.15)
				)
				(justify left bottom)
				(hide yes)
			)
		)
		(property "Voltage" "50V"
			(at 259.08 133.35 0)
			(effects
				(font
					(size 1.27 1.27)
				)
				(justify left bottom)
				(hide yes)
			)
		)
		(property "Dielectric" "X5R"
			(at 261.62 133.35 0)
			(effects
				(font
					(size 1.27 1.27)
				)
				(justify left bottom)
				(hide yes)
			)
		)
		(property "Public" "False"
			(at 264.16 133.35 0)
			(effects
				(font
					(size 1.27 1.27)
				)
				(justify left bottom)
				(hide yes)
			)
		)
		(pin "1"
		)
		(pin "2"
		)
		(instances
			(project "environment-sensor"
				(path ""
					(reference "C19")
					(unit 1)
				)
			)
		)
	)
	(symbol
		(lib_id "antmicropower:+3V3")
		(at 381 35.56 0)
		(unit 1)
		(exclude_from_sim no)
		(in_bom yes)
		(on_board yes)
		(dnp no)
		(fields_autoplaced yes)
		(property "Reference" "#PWR073"
			(at 381 39.37 0)
			(effects
				(font
					(size 1.27 1.27)
				)
				(hide yes)
			)
		)
		(property "Value" "+3V3"
			(at 381 30.48 0)
			(effects
				(font
					(size 1.27 1.27)
				)
			)
		)
		(property "Footprint" ""
			(at 381 35.56 0)
			(effects
				(font
					(size 1.27 1.27)
				)
				(hide yes)
			)
		)
		(property "Datasheet" ""
			(at 381 35.56 0)
			(effects
				(font
					(size 1.27 1.27)
				)
				(hide yes)
			)
		)
		(property "Description" ""
			(at 381 35.56 0)
			(effects
				(font
					(size 1.27 1.27)
				)
				(hide yes)
			)
		)
		(property "Author" "Antmicro"
			(at 396.24 38.1 0)
			(effects
				(font
					(size 1.27 1.27)
					(thickness 0.15)
				)
				(justify left bottom)
				(hide yes)
			)
		)
		(property "License" "Apache-2.0"
			(at 396.24 40.64 0)
			(effects
				(font
					(size 1.27 1.27)
					(thickness 0.15)
				)
				(justify left bottom)
				(hide yes)
			)
		)
		(pin "1"
		)
		(instances
			(project "environment-sensor"
				(path ""
					(reference "#PWR073")
					(unit 1)
				)
			)
		)
	)
	(symbol
		(lib_id "antmicropower:+3V3")
		(at 241.3 99.06 0)
		(mirror y)
		(unit 1)
		(exclude_from_sim no)
		(in_bom yes)
		(on_board yes)
		(dnp no)
		(fields_autoplaced yes)
		(property "Reference" "#PWR036"
			(at 241.3 102.87 0)
			(effects
				(font
					(size 1.27 1.27)
				)
				(hide yes)
			)
		)
		(property "Value" "+3V3"
			(at 241.3 93.98 0)
			(effects
				(font
					(size 1.27 1.27)
				)
			)
		)
		(property "Footprint" ""
			(at 241.3 99.06 0)
			(effects
				(font
					(size 1.27 1.27)
				)
				(hide yes)
			)
		)
		(property "Datasheet" ""
			(at 241.3 99.06 0)
			(effects
				(font
					(size 1.27 1.27)
				)
				(hide yes)
			)
		)
		(property "Description" ""
			(at 241.3 99.06 0)
			(effects
				(font
					(size 1.27 1.27)
				)
				(hide yes)
			)
		)
		(property "Author" "Antmicro"
			(at 226.06 101.6 0)
			(effects
				(font
					(size 1.27 1.27)
					(thickness 0.15)
				)
				(justify left bottom)
				(hide yes)
			)
		)
		(property "License" "Apache-2.0"
			(at 226.06 104.14 0)
			(effects
				(font
					(size 1.27 1.27)
					(thickness 0.15)
				)
				(justify left bottom)
				(hide yes)
			)
		)
		(pin "1"
		)
		(instances
			(project "environment-sensor"
				(path ""
					(reference "#PWR036")
					(unit 1)
				)
			)
		)
	)
	(symbol
		(lib_id "antmicroWire2BoardConnectors:JST_SH_1x4_SM04B-SRSS-TB-LF-SN")
		(at 236.22 259.08 0)
		(mirror x)
		(unit 1)
		(exclude_from_sim no)
		(in_bom yes)
		(on_board yes)
		(dnp no)
		(fields_autoplaced yes)
		(property "Reference" "J2"
			(at 243.84 254 0)
			(effects
				(font
					(size 1.27 1.27)
					(thickness 0.15)
				)
				(justify left)
			)
		)
		(property "Value" "JST_SH_1x4_SM04B-SRSS-TB-LF-SN"
			(at 262.89 251.46 0)
			(effects
				(font
					(size 1.27 1.27)
					(thickness 0.15)
				)
				(justify left bottom)
				(hide yes)
			)
		)
		(property "Footprint" "antmicro-footprints:Conn_JST_SH_1x4_SM04B-SRSS-TB-LF-SN"
			(at 262.89 248.92 0)
			(effects
				(font
					(size 1.27 1.27)
					(thickness 0.15)
				)
				(justify left bottom)
				(hide yes)
			)
		)
		(property "Datasheet" "https://www.jst-mfg.com/product/pdf/eng/eSH.pdf"
			(at 262.89 246.38 0)
			(effects
				(font
					(size 1.27 1.27)
					(thickness 0.15)
				)
				(justify left bottom)
				(hide yes)
			)
		)
		(property "Description" "Pin Header, Right Angle, Wire-to-Board, 1 mm, 1 Rows, 4 Contacts, Surface Mount Right Angle, SH"
			(at 236.22 259.08 0)
			(effects
				(font
					(size 1.27 1.27)
				)
				(hide yes)
			)
		)
		(property "MPN" "SM04B-SRSS-TB(LF)(SN)"
			(at 243.84 251.46 0)
			(effects
				(font
					(size 1.27 1.27)
					(thickness 0.15)
				)
				(justify left)
			)
		)
		(property "Manufacturer" "JST Automotive Connectors"
			(at 262.89 243.84 0)
			(effects
				(font
					(size 1.27 1.27)
					(thickness 0.15)
				)
				(justify left bottom)
				(hide yes)
			)
		)
		(property "Author" "Antmicro"
			(at 262.89 241.3 0)
			(effects
				(font
					(size 1.27 1.27)
					(thickness 0.15)
				)
				(justify left bottom)
				(hide yes)
			)
		)
		(property "License" "Apache-2.0"
			(at 262.89 238.76 0)
			(effects
				(font
					(size 1.27 1.27)
					(thickness 0.15)
				)
				(justify left bottom)
				(hide yes)
			)
		)
		(pin "MP"
		)
		(pin "4"
		)
		(pin "3"
		)
		(pin "2"
		)
		(pin "1"
		)
		(instances
			(project "environment-sensor"
				(path ""
					(reference "J2")
					(unit 1)
				)
			)
		)
	)
	(symbol
		(lib_id "antmicroResistors0402:R_1M_0402")
		(at 40.64 93.98 0)
		(unit 1)
		(exclude_from_sim no)
		(in_bom no)
		(on_board yes)
		(dnp yes)
		(fields_autoplaced yes)
		(property "Reference" "R1"
			(at 40.64 92.71 0)
			(effects
				(font
					(size 1.27 1.27)
					(thickness 0.15)
				)
				(justify left bottom)
			)
		)
		(property "Value" "R_1M_0402"
			(at 60.96 106.68 0)
			(effects
				(font
					(size 1.27 1.27)
					(thickness 0.15)
				)
				(justify left bottom)
				(hide yes)
			)
		)
		(property "Footprint" "antmicro-footprints:R_0402_1005Metric"
			(at 60.96 109.22 0)
			(effects
				(font
					(size 1.27 1.27)
					(thickness 0.15)
				)
				(justify left bottom)
				(hide yes)
			)
		)
		(property "Datasheet" "https://www.bourns.com/docs/product-datasheets/cr.pdf"
			(at 60.96 111.76 0)
			(effects
				(font
					(size 1.27 1.27)
					(thickness 0.15)
				)
				(justify left bottom)
				(hide yes)
			)
		)
		(property "Description" "SMD Chip Resistor, 1 Mohm, ± 1%, 62.5 mW, 0402 [1005 Metric], Thick Film, General Purpose"
			(at 40.64 93.98 0)
			(effects
				(font
					(size 1.27 1.27)
				)
				(hide yes)
			)
		)
		(property "Manufacturer" "Bourns"
			(at 60.96 116.84 0)
			(effects
				(font
					(size 1.27 1.27)
					(thickness 0.15)
				)
				(justify left bottom)
				(hide yes)
			)
		)
		(property "MPN" "CR0402-FX-1004GLF"
			(at 60.96 114.3 0)
			(effects
				(font
					(size 1.27 1.27)
					(thickness 0.15)
				)
				(justify left bottom)
				(hide yes)
			)
		)
		(property "Val" "1M"
			(at 44.45 92.71 0)
			(effects
				(font
					(size 1.27 1.27)
					(thickness 0.15)
				)
				(justify left bottom)
			)
		)
		(property "License" "Apache-2.0"
			(at 60.96 119.38 0)
			(effects
				(font
					(size 1.27 1.27)
					(thickness 0.15)
				)
				(justify left bottom)
				(hide yes)
			)
		)
		(property "Author" "Antmicro"
			(at 60.96 121.92 0)
			(effects
				(font
					(size 1.27 1.27)
					(thickness 0.15)
				)
				(justify left bottom)
				(hide yes)
			)
		)
		(property "Tolerance" "1%"
			(at 60.96 104.14 0)
			(effects
				(font
					(size 1.27 1.27)
				)
				(justify left bottom)
				(hide yes)
			)
		)
		(property "Public" "False"
			(at 60.96 124.46 0)
			(effects
				(font
					(size 1.27 1.27)
				)
				(justify left bottom)
				(hide yes)
			)
		)
		(pin "1"
		)
		(pin "2"
		)
		(instances
			(project "environment-sensor"
				(path ""
					(reference "R1")
					(unit 1)
				)
			)
		)
	)
	(symbol
		(lib_id "antmicroResistors0402:R_0R_0402")
		(at 101.6 193.04 0)
		(unit 1)
		(exclude_from_sim no)
		(in_bom yes)
		(on_board yes)
		(dnp no)
		(fields_autoplaced yes)
		(property "Reference" "R7"
			(at 100.965 191.77 0)
			(effects
				(font
					(size 1.27 1.27)
					(thickness 0.15)
				)
			)
		)
		(property "Value" "R_0R_0402"
			(at 121.92 205.74 0)
			(effects
				(font
					(size 1.27 1.27)
					(thickness 0.15)
				)
				(justify left bottom)
				(hide yes)
			)
		)
		(property "Footprint" "antmicro-footprints:R_0402_1005Metric"
			(at 121.92 208.28 0)
			(effects
				(font
					(size 1.27 1.27)
					(thickness 0.15)
				)
				(justify left bottom)
				(hide yes)
			)
		)
		(property "Datasheet" "https://industrial.panasonic.com/cdbs/www-data/pdf/RDA0000/AOA0000C301.pdf"
			(at 121.92 210.82 0)
			(effects
				(font
					(size 1.27 1.27)
					(thickness 0.15)
				)
				(justify left bottom)
				(hide yes)
			)
		)
		(property "Description" "SMD Chip Resistor, Jumper, 0 ohm, 100 mW, 0402 [1005 Metric], Thick Film, General Purpose"
			(at 101.6 193.04 0)
			(effects
				(font
					(size 1.27 1.27)
				)
				(hide yes)
			)
		)
		(property "Manufacturer" "Panasonic"
			(at 121.92 215.9 0)
			(effects
				(font
					(size 1.27 1.27)
					(thickness 0.15)
				)
				(justify left bottom)
				(hide yes)
			)
		)
		(property "MPN" "ERJ2GE0R00X"
			(at 121.92 213.36 0)
			(effects
				(font
					(size 1.27 1.27)
					(thickness 0.15)
				)
				(justify left bottom)
				(hide yes)
			)
		)
		(property "Val" "0R"
			(at 107.315 191.77 0)
			(effects
				(font
					(size 1.27 1.27)
					(thickness 0.15)
				)
			)
		)
		(property "License" "Apache-2.0"
			(at 121.92 218.44 0)
			(effects
				(font
					(size 1.27 1.27)
					(thickness 0.15)
				)
				(justify left bottom)
				(hide yes)
			)
		)
		(property "Author" "Antmicro"
			(at 121.92 220.98 0)
			(effects
				(font
					(size 1.27 1.27)
					(thickness 0.15)
				)
				(justify left bottom)
				(hide yes)
			)
		)
		(property "Tolerance" "~"
			(at 121.92 203.2 0)
			(effects
				(font
					(size 1.27 1.27)
				)
				(justify left bottom)
				(hide yes)
			)
		)
		(property "Current" "1A"
			(at 104.14 193.04 0)
			(effects
				(font
					(size 1.27 1.27)
					(thickness 0.15)
				)
				(hide yes)
			)
		)
		(property "Public" "False"
			(at 121.92 223.52 0)
			(effects
				(font
					(size 1.27 1.27)
				)
				(justify left bottom)
				(hide yes)
			)
		)
		(pin "1"
		)
		(pin "2"
		)
		(instances
			(project "environment-sensor"
				(path ""
					(reference "R7")
					(unit 1)
				)
			)
		)
	)
	(symbol
		(lib_id "antmicroResistors0402:R_100k_0402")
		(at 306.07 144.78 90)
		(unit 1)
		(exclude_from_sim no)
		(in_bom yes)
		(on_board yes)
		(dnp no)
		(fields_autoplaced yes)
		(property "Reference" "R29"
			(at 303.53 140.9699 90)
			(effects
				(font
					(size 1.27 1.27)
					(thickness 0.15)
				)
				(justify left)
			)
		)
		(property "Value" "R_100k_0402"
			(at 318.77 124.46 0)
			(effects
				(font
					(size 1.27 1.27)
					(thickness 0.15)
				)
				(justify left bottom)
				(hide yes)
			)
		)
		(property "Footprint" "antmicro-footprints:R_0402_1005Metric"
			(at 321.31 124.46 0)
			(effects
				(font
					(size 1.27 1.27)
					(thickness 0.15)
				)
				(justify left bottom)
				(hide yes)
			)
		)
		(property "Datasheet" "https://www.bourns.com/docs/product-datasheets/cr.pdf"
			(at 323.85 124.46 0)
			(effects
				(font
					(size 1.27 1.27)
					(thickness 0.15)
				)
				(justify left bottom)
				(hide yes)
			)
		)
		(property "Description" "SMD Chip Resistor, 100 kohm, ± 1%, 62.5 mW, 0402 [1005 Metric], Thick Film, General Purpose"
			(at 306.07 144.78 0)
			(effects
				(font
					(size 1.27 1.27)
				)
				(hide yes)
			)
		)
		(property "Manufacturer" "Bourns"
			(at 328.93 124.46 0)
			(effects
				(font
					(size 1.27 1.27)
					(thickness 0.15)
				)
				(justify left bottom)
				(hide yes)
			)
		)
		(property "MPN" "CR0402-FX-1003GLF"
			(at 326.39 124.46 0)
			(effects
				(font
					(size 1.27 1.27)
					(thickness 0.15)
				)
				(justify left bottom)
				(hide yes)
			)
		)
		(property "Val" "100k"
			(at 303.53 143.5099 90)
			(effects
				(font
					(size 1.27 1.27)
					(thickness 0.15)
				)
				(justify left)
			)
		)
		(property "License" "Apache-2.0"
			(at 331.47 124.46 0)
			(effects
				(font
					(size 1.27 1.27)
					(thickness 0.15)
				)
				(justify left bottom)
				(hide yes)
			)
		)
		(property "Author" "Antmicro"
			(at 334.01 124.46 0)
			(effects
				(font
					(size 1.27 1.27)
					(thickness 0.15)
				)
				(justify left bottom)
				(hide yes)
			)
		)
		(property "Tolerance" "1%"
			(at 316.23 124.46 0)
			(effects
				(font
					(size 1.27 1.27)
				)
				(justify left bottom)
				(hide yes)
			)
		)
		(property "Public" "False"
			(at 336.55 124.46 0)
			(effects
				(font
					(size 1.27 1.27)
				)
				(justify left bottom)
				(hide yes)
			)
		)
		(pin "1"
		)
		(pin "2"
		)
		(instances
			(project "environment-sensor"
				(path ""
					(reference "R29")
					(unit 1)
				)
			)
		)
	)
	(symbol
		(lib_id "antmicropower:GNDREF")
		(at 35.56 106.68 0)
		(unit 1)
		(exclude_from_sim no)
		(in_bom yes)
		(on_board yes)
		(dnp no)
		(fields_autoplaced yes)
		(property "Reference" "#PWR01"
			(at 35.56 113.03 0)
			(effects
				(font
					(size 1.27 1.27)
				)
				(hide yes)
			)
		)
		(property "Value" "GNDREF"
			(at 35.56 111.76 0)
			(effects
				(font
					(size 1.27 1.27)
				)
			)
		)
		(property "Footprint" ""
			(at 35.56 106.68 0)
			(effects
				(font
					(size 1.27 1.27)
				)
				(hide yes)
			)
		)
		(property "Datasheet" ""
			(at 35.56 106.68 0)
			(effects
				(font
					(size 1.27 1.27)
				)
				(hide yes)
			)
		)
		(property "Description" ""
			(at 35.56 106.68 0)
			(effects
				(font
					(size 1.27 1.27)
				)
				(hide yes)
			)
		)
		(pin "1"
		)
		(instances
			(project "environment-sensor"
				(path ""
					(reference "#PWR01")
					(unit 1)
				)
			)
		)
	)
	(symbol
		(lib_id "antmicroTestPoints:TP_1.5mm_SMD")
		(at 147.32 265.43 180)
		(unit 1)
		(exclude_from_sim no)
		(in_bom yes)
		(on_board yes)
		(dnp no)
		(fields_autoplaced yes)
		(property "Reference" "TP6"
			(at 140.335 263.525 0)
			(effects
				(font
					(size 1.27 1.27)
					(thickness 0.15)
				)
			)
		)
		(property "Value" "TP_1.5mm_SMD"
			(at 132.08 257.81 0)
			(effects
				(font
					(size 1.27 1.27)
					(thickness 0.15)
				)
				(justify left bottom)
				(hide yes)
			)
		)
		(property "Footprint" "antmicro-footprints:TP_SMD_1.5mm"
			(at 132.08 255.27 0)
			(effects
				(font
					(size 1.27 1.27)
					(thickness 0.15)
				)
				(justify left bottom)
				(hide yes)
			)
		)
		(property "Datasheet" ""
			(at 132.08 252.73 0)
			(effects
				(font
					(size 1.27 1.27)
					(thickness 0.15)
				)
				(justify left bottom)
				(hide yes)
			)
		)
		(property "Description" "test point, SMT"
			(at 147.32 265.43 0)
			(effects
				(font
					(size 1.27 1.27)
				)
				(hide yes)
			)
		)
		(property "MPN" ""
			(at 147.32 265.43 0)
			(effects
				(font
					(size 1.27 1.27)
				)
				(hide yes)
			)
		)
		(property "Manufacturer" ""
			(at 147.32 265.43 0)
			(effects
				(font
					(size 1.27 1.27)
				)
				(hide yes)
			)
		)
		(property "Author" "Antmicro"
			(at 132.08 250.19 0)
			(effects
				(font
					(size 1.27 1.27)
					(thickness 0.15)
				)
				(justify left bottom)
				(hide yes)
			)
		)
		(property "License" "Apache-2.0"
			(at 132.08 247.65 0)
			(effects
				(font
					(size 1.27 1.27)
					(thickness 0.15)
				)
				(justify left bottom)
				(hide yes)
			)
		)
		(property "Public" "False"
			(at 132.08 245.11 0)
			(effects
				(font
					(size 1.27 1.27)
				)
				(justify left bottom)
				(hide yes)
			)
		)
		(pin "1"
		)
		(instances
			(project "environment-sensor"
				(path ""
					(reference "TP6")
					(unit 1)
				)
			)
		)
	)
	(symbol
		(lib_id "antmicroCapacitors0402:C_10p_0402")
		(at 287.02 212.09 270)
		(mirror x)
		(unit 1)
		(exclude_from_sim no)
		(in_bom yes)
		(on_board yes)
		(dnp no)
		(fields_autoplaced yes)
		(property "Reference" "C21"
			(at 289.56 208.2735 90)
			(effects
				(font
					(size 1.27 1.27)
					(thickness 0.15)
				)
				(justify left)
			)
		)
		(property "Value" "C_10p_0402"
			(at 276.86 191.77 0)
			(effects
				(font
					(size 1.27 1.27)
					(thickness 0.15)
				)
				(justify left bottom)
				(hide yes)
			)
		)
		(property "Footprint" "antmicro-footprints:C_0402_1005Metric"
			(at 274.32 191.77 0)
			(effects
				(font
					(size 1.27 1.27)
					(thickness 0.15)
				)
				(justify left bottom)
				(hide yes)
			)
		)
		(property "Datasheet" "https://www.murata.com/products/productdetail?partno=GCM1555C1H100GA16%23"
			(at 271.78 191.77 0)
			(effects
				(font
					(size 1.27 1.27)
					(thickness 0.15)
				)
				(justify left bottom)
				(hide yes)
			)
		)
		(property "Description" "SMD Multilayer Ceramic Capacitor, 10 pF, 50 V, 0402 [1005 Metric], ± 2%, C0G / NP0, GCM"
			(at 287.02 212.09 0)
			(effects
				(font
					(size 1.27 1.27)
				)
				(hide yes)
			)
		)
		(property "Manufacturer" "Murata"
			(at 266.7 191.77 0)
			(effects
				(font
					(size 1.27 1.27)
					(thickness 0.15)
				)
				(justify left bottom)
				(hide yes)
			)
		)
		(property "MPN" "GCM1555C1H100GA16D"
			(at 269.24 191.77 0)
			(effects
				(font
					(size 1.27 1.27)
					(thickness 0.15)
				)
				(justify left bottom)
				(hide yes)
			)
		)
		(property "Val" "10p"
			(at 289.56 210.8135 90)
			(effects
				(font
					(size 1.27 1.27)
					(thickness 0.15)
				)
				(justify left)
			)
		)
		(property "License" "Apache-2.0"
			(at 264.16 191.77 0)
			(effects
				(font
					(size 1.27 1.27)
					(thickness 0.15)
				)
				(justify left bottom)
				(hide yes)
			)
		)
		(property "Author" "Antmicro"
			(at 261.62 191.77 0)
			(effects
				(font
					(size 1.27 1.27)
					(thickness 0.15)
				)
				(justify left bottom)
				(hide yes)
			)
		)
		(property "Voltage" "50V"
			(at 259.08 191.77 0)
			(effects
				(font
					(size 1.27 1.27)
				)
				(justify left bottom)
				(hide yes)
			)
		)
		(property "Dielectric" "C0G"
			(at 256.54 191.77 0)
			(effects
				(font
					(size 1.27 1.27)
				)
				(justify left bottom)
				(hide yes)
			)
		)
		(property "Public" "False"
			(at 254 191.77 0)
			(effects
				(font
					(size 1.27 1.27)
				)
				(justify left bottom)
				(hide yes)
			)
		)
		(pin "1"
		)
		(pin "2"
		)
		(instances
			(project "environment-sensor"
				(path ""
					(reference "C21")
					(unit 1)
				)
			)
		)
	)
	(symbol
		(lib_id "antmicropower:+3V3")
		(at 353.06 229.87 0)
		(mirror y)
		(unit 1)
		(exclude_from_sim no)
		(in_bom yes)
		(on_board yes)
		(dnp no)
		(fields_autoplaced yes)
		(property "Reference" "#PWR064"
			(at 353.06 233.68 0)
			(effects
				(font
					(size 1.27 1.27)
				)
				(hide yes)
			)
		)
		(property "Value" "+3V3"
			(at 353.06 224.79 0)
			(effects
				(font
					(size 1.27 1.27)
				)
			)
		)
		(property "Footprint" ""
			(at 353.06 229.87 0)
			(effects
				(font
					(size 1.27 1.27)
				)
				(hide yes)
			)
		)
		(property "Datasheet" ""
			(at 353.06 229.87 0)
			(effects
				(font
					(size 1.27 1.27)
				)
				(hide yes)
			)
		)
		(property "Description" ""
			(at 353.06 229.87 0)
			(effects
				(font
					(size 1.27 1.27)
				)
				(hide yes)
			)
		)
		(property "Author" "Antmicro"
			(at 337.82 232.41 0)
			(effects
				(font
					(size 1.27 1.27)
					(thickness 0.15)
				)
				(justify left bottom)
				(hide yes)
			)
		)
		(property "License" "Apache-2.0"
			(at 337.82 234.95 0)
			(effects
				(font
					(size 1.27 1.27)
					(thickness 0.15)
				)
				(justify left bottom)
				(hide yes)
			)
		)
		(pin "1"
		)
		(instances
			(project "environment-sensor"
				(path ""
					(reference "#PWR064")
					(unit 1)
				)
			)
		)
	)
	(symbol
		(lib_id "antmicroMechanicalParts:oshw_logo")
		(at 163.83 274.32 0)
		(unit 1)
		(exclude_from_sim no)
		(in_bom no)
		(on_board yes)
		(dnp no)
		(fields_autoplaced yes)
		(property "Reference" "N2"
			(at 170.18 272.3362 0)
			(effects
				(font
					(size 1.27 1.27)
					(thickness 0.15)
				)
				(justify left)
			)
		)
		(property "Value" "oshw_logo"
			(at 170.18 274.8762 0)
			(effects
				(font
					(size 1.27 1.27)
					(thickness 0.15)
				)
				(justify left)
			)
		)
		(property "Footprint" "antmicro-footprints:oshw-logo"
			(at 179.07 284.48 0)
			(effects
				(font
					(size 1.27 1.27)
					(thickness 0.15)
				)
				(justify left bottom)
				(hide yes)
			)
		)
		(property "Datasheet" ""
			(at 179.07 287.02 0)
			(effects
				(font
					(size 1.27 1.27)
					(thickness 0.15)
				)
				(justify left bottom)
				(hide yes)
			)
		)
		(property "Description" "Mechanical part"
			(at 163.83 274.32 0)
			(effects
				(font
					(size 1.27 1.27)
				)
				(hide yes)
			)
		)
		(property "Author" "Antmicro"
			(at 179.07 289.56 0)
			(effects
				(font
					(size 1.27 1.27)
					(thickness 0.15)
				)
				(justify left bottom)
				(hide yes)
			)
		)
		(property "License" "Apache-2.0"
			(at 179.07 292.1 0)
			(effects
				(font
					(size 1.27 1.27)
					(thickness 0.15)
				)
				(justify left bottom)
				(hide yes)
			)
		)
		(property "MPN" ""
			(at 163.83 274.32 0)
			(effects
				(font
					(size 1.27 1.27)
				)
				(hide yes)
			)
		)
		(property "Manufacturer" ""
			(at 179.07 294.64 0)
			(effects
				(font
					(size 1.27 1.27)
					(thickness 0.15)
				)
				(justify left bottom)
				(hide yes)
			)
		)
		(property "Public" "False"
			(at 179.07 294.64 0)
			(effects
				(font
					(size 1.27 1.27)
				)
				(justify left bottom)
				(hide yes)
			)
		)
		(instances
			(project "environment-sensor"
				(path ""
					(reference "N2")
					(unit 1)
				)
			)
		)
	)
	(symbol
		(lib_id "antmicroResistors0402:R_100k_0402")
		(at 200.66 143.51 90)
		(unit 1)
		(exclude_from_sim no)
		(in_bom yes)
		(on_board yes)
		(dnp no)
		(fields_autoplaced yes)
		(property "Reference" "R19"
			(at 195.58 139.7 90)
			(effects
				(font
					(size 1.27 1.27)
					(thickness 0.15)
				)
				(justify right)
			)
		)
		(property "Value" "R_100k_0402"
			(at 213.36 123.19 0)
			(effects
				(font
					(size 1.27 1.27)
					(thickness 0.15)
				)
				(justify left bottom)
				(hide yes)
			)
		)
		(property "Footprint" "antmicro-footprints:R_0402_1005Metric"
			(at 215.9 123.19 0)
			(effects
				(font
					(size 1.27 1.27)
					(thickness 0.15)
				)
				(justify left bottom)
				(hide yes)
			)
		)
		(property "Datasheet" "https://www.bourns.com/docs/product-datasheets/cr.pdf"
			(at 218.44 123.19 0)
			(effects
				(font
					(size 1.27 1.27)
					(thickness 0.15)
				)
				(justify left bottom)
				(hide yes)
			)
		)
		(property "Description" "SMD Chip Resistor, 100 kohm, ± 1%, 62.5 mW, 0402 [1005 Metric], Thick Film, General Purpose"
			(at 200.66 143.51 0)
			(effects
				(font
					(size 1.27 1.27)
				)
				(hide yes)
			)
		)
		(property "Manufacturer" "Bourns"
			(at 223.52 123.19 0)
			(effects
				(font
					(size 1.27 1.27)
					(thickness 0.15)
				)
				(justify left bottom)
				(hide yes)
			)
		)
		(property "MPN" "CR0402-FX-1003GLF"
			(at 220.98 123.19 0)
			(effects
				(font
					(size 1.27 1.27)
					(thickness 0.15)
				)
				(justify left bottom)
				(hide yes)
			)
		)
		(property "Val" "100k"
			(at 194.31 142.24 90)
			(effects
				(font
					(size 1.27 1.27)
					(thickness 0.15)
				)
				(justify right)
			)
		)
		(property "License" "Apache-2.0"
			(at 226.06 123.19 0)
			(effects
				(font
					(size 1.27 1.27)
					(thickness 0.15)
				)
				(justify left bottom)
				(hide yes)
			)
		)
		(property "Author" "Antmicro"
			(at 228.6 123.19 0)
			(effects
				(font
					(size 1.27 1.27)
					(thickness 0.15)
				)
				(justify left bottom)
				(hide yes)
			)
		)
		(property "Tolerance" "1%"
			(at 210.82 123.19 0)
			(effects
				(font
					(size 1.27 1.27)
				)
				(justify left bottom)
				(hide yes)
			)
		)
		(property "Public" "False"
			(at 231.14 123.19 0)
			(effects
				(font
					(size 1.27 1.27)
				)
				(justify left bottom)
				(hide yes)
			)
		)
		(pin "1"
		)
		(pin "2"
		)
		(instances
			(project "environment-sensor"
				(path ""
					(reference "R19")
					(unit 1)
				)
			)
		)
	)
	(symbol
		(lib_id "antmicroMechanicalParts:MP_Pad5.4mm_Drill2.7mm")
		(at 269.24 281.94 90)
		(unit 1)
		(exclude_from_sim no)
		(in_bom no)
		(on_board yes)
		(dnp no)
		(fields_autoplaced yes)
		(property "Reference" "MP3"
			(at 273.05 275.59 90)
			(effects
				(font
					(size 1.27 1.27)
					(thickness 0.15)
				)
				(justify right)
			)
		)
		(property "Value" "MP_Pad5.4mm_Drill2.7mm"
			(at 273.05 278.13 90)
			(effects
				(font
					(size 1.27 1.27)
					(thickness 0.15)
				)
				(justify right)
			)
		)
		(property "Footprint" "antmicro-footprints:MP_Pad5.4mm_Drill2.7mm"
			(at 276.86 261.62 0)
			(effects
				(font
					(size 1.27 1.27)
					(thickness 0.15)
				)
				(justify left bottom)
				(hide yes)
			)
		)
		(property "Datasheet" ""
			(at 284.81 265.1 0)
			(effects
				(font
					(size 1.27 1.27)
					(thickness 0.15)
				)
				(justify left bottom)
				(hide yes)
			)
		)
		(property "Description" "Mechanical part"
			(at 269.24 281.94 0)
			(effects
				(font
					(size 1.27 1.27)
				)
				(hide yes)
			)
		)
		(property "Author" "Antmicro"
			(at 279.4 261.62 0)
			(effects
				(font
					(size 1.27 1.27)
					(thickness 0.15)
				)
				(justify left bottom)
				(hide yes)
			)
		)
		(property "License" "Apache-2.0"
			(at 281.94 261.62 0)
			(effects
				(font
					(size 1.27 1.27)
					(thickness 0.15)
				)
				(justify left bottom)
				(hide yes)
			)
		)
		(property "Public" "False"
			(at 284.48 261.62 0)
			(effects
				(font
					(size 1.27 1.27)
				)
				(justify left bottom)
				(hide yes)
			)
		)
		(pin "1"
		)
		(instances
			(project "environment-sensor"
				(path ""
					(reference "MP3")
					(unit 1)
				)
			)
		)
	)
	(symbol
		(lib_id "antmicropower:GND")
		(at 370.84 228.6 0)
		(mirror y)
		(unit 1)
		(exclude_from_sim no)
		(in_bom yes)
		(on_board yes)
		(dnp no)
		(fields_autoplaced yes)
		(property "Reference" "#PWR071"
			(at 370.84 234.95 0)
			(effects
				(font
					(size 1.27 1.27)
				)
				(hide yes)
			)
		)
		(property "Value" "GND"
			(at 373.38 229.8699 0)
			(effects
				(font
					(size 1.27 1.27)
				)
				(justify right)
			)
		)
		(property "Footprint" ""
			(at 370.84 228.6 0)
			(effects
				(font
					(size 1.27 1.27)
				)
				(hide yes)
			)
		)
		(property "Datasheet" ""
			(at 370.84 228.6 0)
			(effects
				(font
					(size 1.27 1.27)
				)
				(hide yes)
			)
		)
		(property "Description" ""
			(at 370.84 228.6 0)
			(effects
				(font
					(size 1.27 1.27)
				)
				(hide yes)
			)
		)
		(property "Author" "Antmicro"
			(at 361.95 236.22 0)
			(effects
				(font
					(size 1.27 1.27)
					(thickness 0.15)
				)
				(justify left bottom)
				(hide yes)
			)
		)
		(property "License" "Apache-2.0"
			(at 361.95 238.76 0)
			(effects
				(font
					(size 1.27 1.27)
					(thickness 0.15)
				)
				(justify left bottom)
				(hide yes)
			)
		)
		(pin "1"
		)
		(instances
			(project "environment-sensor"
				(path ""
					(reference "#PWR071")
					(unit 1)
				)
			)
		)
	)
	(symbol
		(lib_id "antmicroResistors0402:R_5k1_0402")
		(at 74.93 104.14 90)
		(unit 1)
		(exclude_from_sim no)
		(in_bom yes)
		(on_board yes)
		(dnp no)
		(fields_autoplaced yes)
		(property "Reference" "R3"
			(at 72.39 100.3299 90)
			(effects
				(font
					(size 1.27 1.27)
					(thickness 0.15)
				)
				(justify left)
			)
		)
		(property "Value" "R_5k1_0402"
			(at 87.63 83.82 0)
			(effects
				(font
					(size 1.27 1.27)
					(thickness 0.15)
				)
				(justify left bottom)
				(hide yes)
			)
		)
		(property "Footprint" "antmicro-footprints:R_0402_1005Metric"
			(at 90.17 83.82 0)
			(effects
				(font
					(size 1.27 1.27)
					(thickness 0.15)
				)
				(justify left bottom)
				(hide yes)
			)
		)
		(property "Datasheet" "https://www.bourns.com/docs/product-datasheets/cr.pdf"
			(at 92.71 83.82 0)
			(effects
				(font
					(size 1.27 1.27)
					(thickness 0.15)
				)
				(justify left bottom)
				(hide yes)
			)
		)
		(property "Description" "SMD Chip Resistor, 5.1 kohm, ± 1%, 63 mW, 0402 [1005 Metric], Thick Film, General Purpose"
			(at 74.93 104.14 0)
			(effects
				(font
					(size 1.27 1.27)
				)
				(hide yes)
			)
		)
		(property "Manufacturer" "Bourns"
			(at 97.79 83.82 0)
			(effects
				(font
					(size 1.27 1.27)
					(thickness 0.15)
				)
				(justify left bottom)
				(hide yes)
			)
		)
		(property "MPN" "CR0402-FX-5101GLF"
			(at 95.25 83.82 0)
			(effects
				(font
					(size 1.27 1.27)
					(thickness 0.15)
				)
				(justify left bottom)
				(hide yes)
			)
		)
		(property "Val" "5k1"
			(at 72.39 102.8699 90)
			(effects
				(font
					(size 1.27 1.27)
					(thickness 0.15)
				)
				(justify left)
			)
		)
		(property "License" "Apache-2.0"
			(at 100.33 83.82 0)
			(effects
				(font
					(size 1.27 1.27)
					(thickness 0.15)
				)
				(justify left bottom)
				(hide yes)
			)
		)
		(property "Author" "Antmicro"
			(at 102.87 83.82 0)
			(effects
				(font
					(size 1.27 1.27)
					(thickness 0.15)
				)
				(justify left bottom)
				(hide yes)
			)
		)
		(property "Tolerance" "1%"
			(at 85.09 83.82 0)
			(effects
				(font
					(size 1.27 1.27)
				)
				(justify left bottom)
				(hide yes)
			)
		)
		(property "Public" "False"
			(at 105.41 83.82 0)
			(effects
				(font
					(size 1.27 1.27)
				)
				(justify left bottom)
				(hide yes)
			)
		)
		(pin "1"
		)
		(pin "2"
		)
		(instances
			(project "environment-sensor"
				(path ""
					(reference "R3")
					(unit 1)
				)
			)
		)
	)
	(symbol
		(lib_id "antmicroMechanicalParts:MP_Pad5.4mm_Drill2.7mm")
		(at 269.24 271.78 90)
		(unit 1)
		(exclude_from_sim no)
		(in_bom no)
		(on_board yes)
		(dnp no)
		(fields_autoplaced yes)
		(property "Reference" "MP2"
			(at 273.05 265.43 90)
			(effects
				(font
					(size 1.27 1.27)
					(thickness 0.15)
				)
				(justify right)
			)
		)
		(property "Value" "MP_Pad5.4mm_Drill2.7mm"
			(at 273.05 267.97 90)
			(effects
				(font
					(size 1.27 1.27)
					(thickness 0.15)
				)
				(justify right)
			)
		)
		(property "Footprint" "antmicro-footprints:MP_Pad5.4mm_Drill2.7mm"
			(at 276.86 251.46 0)
			(effects
				(font
					(size 1.27 1.27)
					(thickness 0.15)
				)
				(justify left bottom)
				(hide yes)
			)
		)
		(property "Datasheet" ""
			(at 284.81 254.94 0)
			(effects
				(font
					(size 1.27 1.27)
					(thickness 0.15)
				)
				(justify left bottom)
				(hide yes)
			)
		)
		(property "Description" "Mechanical part"
			(at 269.24 271.78 0)
			(effects
				(font
					(size 1.27 1.27)
				)
				(hide yes)
			)
		)
		(property "Author" "Antmicro"
			(at 279.4 251.46 0)
			(effects
				(font
					(size 1.27 1.27)
					(thickness 0.15)
				)
				(justify left bottom)
				(hide yes)
			)
		)
		(property "License" "Apache-2.0"
			(at 281.94 251.46 0)
			(effects
				(font
					(size 1.27 1.27)
					(thickness 0.15)
				)
				(justify left bottom)
				(hide yes)
			)
		)
		(property "Public" "False"
			(at 284.48 251.46 0)
			(effects
				(font
					(size 1.27 1.27)
				)
				(justify left bottom)
				(hide yes)
			)
		)
		(pin "1"
		)
		(instances
			(project "environment-sensor"
				(path ""
					(reference "MP2")
					(unit 1)
				)
			)
		)
	)
	(symbol
		(lib_id "antmicropower:GND")
		(at 299.72 217.17 0)
		(mirror y)
		(unit 1)
		(exclude_from_sim no)
		(in_bom yes)
		(on_board yes)
		(dnp no)
		(fields_autoplaced yes)
		(property "Reference" "#PWR052"
			(at 299.72 223.52 0)
			(effects
				(font
					(size 1.27 1.27)
				)
				(hide yes)
			)
		)
		(property "Value" "GND"
			(at 299.72 222.25 0)
			(effects
				(font
					(size 1.27 1.27)
				)
			)
		)
		(property "Footprint" ""
			(at 299.72 217.17 0)
			(effects
				(font
					(size 1.27 1.27)
				)
				(hide yes)
			)
		)
		(property "Datasheet" ""
			(at 299.72 217.17 0)
			(effects
				(font
					(size 1.27 1.27)
				)
				(hide yes)
			)
		)
		(property "Description" ""
			(at 299.72 217.17 0)
			(effects
				(font
					(size 1.27 1.27)
				)
				(hide yes)
			)
		)
		(property "Author" "Antmicro"
			(at 290.83 224.79 0)
			(effects
				(font
					(size 1.27 1.27)
					(thickness 0.15)
				)
				(justify left bottom)
				(hide yes)
			)
		)
		(property "License" "Apache-2.0"
			(at 290.83 227.33 0)
			(effects
				(font
					(size 1.27 1.27)
					(thickness 0.15)
				)
				(justify left bottom)
				(hide yes)
			)
		)
		(pin "1"
		)
		(instances
			(project "environment-sensor"
				(path ""
					(reference "#PWR052")
					(unit 1)
				)
			)
		)
	)
	(symbol
		(lib_id "antmicroTVSDiodes:TPD2E009_SOT-9X3")
		(at 114.3 60.96 270)
		(unit 1)
		(exclude_from_sim no)
		(in_bom yes)
		(on_board yes)
		(dnp no)
		(fields_autoplaced yes)
		(property "Reference" "D5"
			(at 111.76 72.39 90)
			(effects
				(font
					(size 1.27 1.27)
					(thickness 0.15)
				)
			)
		)
		(property "Value" "TPD2E009_SOT-9X3"
			(at 111.76 74.93 90)
			(effects
				(font
					(size 1.27 1.27)
					(thickness 0.15)
				)
			)
		)
		(property "Footprint" "antmicro-footprints:SOT-723"
			(at 109.22 76.2 0)
			(effects
				(font
					(size 1.27 1.27)
					(thickness 0.15)
				)
				(justify left bottom)
				(hide yes)
			)
		)
		(property "Datasheet" "https://www.ti.com/lit/ds/symlink/tpd2e009.pdf?ts=1597910439511&ref_url=https%253A%252F%252Fwww.google.com%252F"
			(at 106.68 76.2 0)
			(effects
				(font
					(size 1.27 1.27)
					(thickness 0.15)
				)
				(justify left bottom)
				(hide yes)
			)
		)
		(property "Description" "TVS diode array, 8 kV, SOT-723, 5.5 V, 0.9 pF"
			(at 114.3 60.96 0)
			(effects
				(font
					(size 1.27 1.27)
				)
				(hide yes)
			)
		)
		(property "MPN" "TPD2E009DRTR"
			(at 104.14 76.2 0)
			(effects
				(font
					(size 1.27 1.27)
					(thickness 0.15)
				)
				(justify left bottom)
				(hide yes)
			)
		)
		(property "Manufacturer" "Texas Instruments"
			(at 101.6 76.2 0)
			(effects
				(font
					(size 1.27 1.27)
					(thickness 0.15)
				)
				(justify left bottom)
				(hide yes)
			)
		)
		(property "Author" "Antmicro"
			(at 99.06 76.2 0)
			(effects
				(font
					(size 1.27 1.27)
					(thickness 0.15)
				)
				(justify left bottom)
				(hide yes)
			)
		)
		(property "License" "Apache-2.0"
			(at 96.52 76.2 0)
			(effects
				(font
					(size 1.27 1.27)
					(thickness 0.15)
				)
				(justify left bottom)
				(hide yes)
			)
		)
		(pin "1"
		)
		(pin "2"
		)
		(pin "3"
		)
		(instances
			(project "environment-sensor"
				(path ""
					(reference "D5")
					(unit 1)
				)
			)
		)
	)
	(symbol
		(lib_id "antmicroCapacitors0402:C_4u7_0402")
		(at 36.83 185.42 90)
		(unit 1)
		(exclude_from_sim no)
		(in_bom yes)
		(on_board yes)
		(dnp no)
		(fields_autoplaced yes)
		(property "Reference" "C1"
			(at 38.735 181.61 90)
			(effects
				(font
					(size 1.27 1.27)
					(thickness 0.15)
				)
				(justify right)
			)
		)
		(property "Value" "C_4u7_0402"
			(at 46.99 165.1 0)
			(effects
				(font
					(size 1.27 1.27)
					(thickness 0.15)
				)
				(justify left bottom)
				(hide yes)
			)
		)
		(property "Footprint" "antmicro-footprints:C_0402_1005Metric"
			(at 49.53 165.1 0)
			(effects
				(font
					(size 1.27 1.27)
					(thickness 0.15)
				)
				(justify left bottom)
				(hide yes)
			)
		)
		(property "Datasheet" "https://www.murata.com/products/productdetail?partno=GRM155R61A475MEAA%23"
			(at 52.07 165.1 0)
			(effects
				(font
					(size 1.27 1.27)
					(thickness 0.15)
				)
				(justify left bottom)
				(hide yes)
			)
		)
		(property "Description" "SMD Multilayer Ceramic Capacitor, 4.7 µF, 10 V, 0402 [1005 Metric], ± 20%, X5R, GRM Series"
			(at 36.83 185.42 0)
			(effects
				(font
					(size 1.27 1.27)
				)
				(hide yes)
			)
		)
		(property "Manufacturer" "Murata"
			(at 57.15 165.1 0)
			(effects
				(font
					(size 1.27 1.27)
					(thickness 0.15)
				)
				(justify left bottom)
				(hide yes)
			)
		)
		(property "MPN" "GRM155R61A475MEAAD"
			(at 54.61 165.1 0)
			(effects
				(font
					(size 1.27 1.27)
					(thickness 0.15)
				)
				(justify left bottom)
				(hide yes)
			)
		)
		(property "Val" "4u7"
			(at 38.735 184.15 90)
			(effects
				(font
					(size 1.27 1.27)
					(thickness 0.15)
				)
				(justify right)
			)
		)
		(property "License" "Apache-2.0"
			(at 59.69 165.1 0)
			(effects
				(font
					(size 1.27 1.27)
					(thickness 0.15)
				)
				(justify left bottom)
				(hide yes)
			)
		)
		(property "Author" "Antmicro"
			(at 62.23 165.1 0)
			(effects
				(font
					(size 1.27 1.27)
					(thickness 0.15)
				)
				(justify left bottom)
				(hide yes)
			)
		)
		(property "Voltage" ""
			(at 64.77 165.1 0)
			(effects
				(font
					(size 1.27 1.27)
				)
				(justify left bottom)
				(hide yes)
			)
		)
		(property "Dielectric" ""
			(at 67.31 165.1 0)
			(effects
				(font
					(size 1.27 1.27)
				)
				(justify left bottom)
				(hide yes)
			)
		)
		(property "Public" "False"
			(at 69.85 165.1 0)
			(effects
				(font
					(size 1.27 1.27)
				)
				(justify left bottom)
				(hide yes)
			)
		)
		(pin "1"
		)
		(pin "2"
		)
		(instances
			(project "environment-sensor"
				(path ""
					(reference "C1")
					(unit 1)
				)
			)
		)
	)
	(symbol
		(lib_id "antmicroResistors0402:R_0R_0402")
		(at 101.6 195.58 0)
		(unit 1)
		(exclude_from_sim no)
		(in_bom yes)
		(on_board yes)
		(dnp no)
		(fields_autoplaced yes)
		(property "Reference" "R8"
			(at 100.965 194.31 0)
			(effects
				(font
					(size 1.27 1.27)
					(thickness 0.15)
				)
			)
		)
		(property "Value" "R_0R_0402"
			(at 121.92 208.28 0)
			(effects
				(font
					(size 1.27 1.27)
					(thickness 0.15)
				)
				(justify left bottom)
				(hide yes)
			)
		)
		(property "Footprint" "antmicro-footprints:R_0402_1005Metric"
			(at 121.92 210.82 0)
			(effects
				(font
					(size 1.27 1.27)
					(thickness 0.15)
				)
				(justify left bottom)
				(hide yes)
			)
		)
		(property "Datasheet" "https://industrial.panasonic.com/cdbs/www-data/pdf/RDA0000/AOA0000C301.pdf"
			(at 121.92 213.36 0)
			(effects
				(font
					(size 1.27 1.27)
					(thickness 0.15)
				)
				(justify left bottom)
				(hide yes)
			)
		)
		(property "Description" "SMD Chip Resistor, Jumper, 0 ohm, 100 mW, 0402 [1005 Metric], Thick Film, General Purpose"
			(at 101.6 195.58 0)
			(effects
				(font
					(size 1.27 1.27)
				)
				(hide yes)
			)
		)
		(property "Manufacturer" "Panasonic"
			(at 121.92 218.44 0)
			(effects
				(font
					(size 1.27 1.27)
					(thickness 0.15)
				)
				(justify left bottom)
				(hide yes)
			)
		)
		(property "MPN" "ERJ2GE0R00X"
			(at 121.92 215.9 0)
			(effects
				(font
					(size 1.27 1.27)
					(thickness 0.15)
				)
				(justify left bottom)
				(hide yes)
			)
		)
		(property "Val" "0R"
			(at 107.315 194.31 0)
			(effects
				(font
					(size 1.27 1.27)
					(thickness 0.15)
				)
			)
		)
		(property "License" "Apache-2.0"
			(at 121.92 220.98 0)
			(effects
				(font
					(size 1.27 1.27)
					(thickness 0.15)
				)
				(justify left bottom)
				(hide yes)
			)
		)
		(property "Author" "Antmicro"
			(at 121.92 223.52 0)
			(effects
				(font
					(size 1.27 1.27)
					(thickness 0.15)
				)
				(justify left bottom)
				(hide yes)
			)
		)
		(property "Tolerance" "~"
			(at 121.92 205.74 0)
			(effects
				(font
					(size 1.27 1.27)
				)
				(justify left bottom)
				(hide yes)
			)
		)
		(property "Current" "1A"
			(at 104.14 195.58 0)
			(effects
				(font
					(size 1.27 1.27)
					(thickness 0.15)
				)
				(hide yes)
			)
		)
		(property "Public" "False"
			(at 121.92 226.06 0)
			(effects
				(font
					(size 1.27 1.27)
				)
				(justify left bottom)
				(hide yes)
			)
		)
		(pin "1"
		)
		(pin "2"
		)
		(instances
			(project "environment-sensor"
				(path ""
					(reference "R8")
					(unit 1)
				)
			)
		)
	)
	(symbol
		(lib_id "antmicropower:GND")
		(at 386.08 73.66 0)
		(mirror y)
		(unit 1)
		(exclude_from_sim no)
		(in_bom yes)
		(on_board yes)
		(dnp no)
		(fields_autoplaced yes)
		(property "Reference" "#PWR075"
			(at 386.08 80.01 0)
			(effects
				(font
					(size 1.27 1.27)
				)
				(hide yes)
			)
		)
		(property "Value" "GND"
			(at 386.08 78.74 0)
			(effects
				(font
					(size 1.27 1.27)
				)
			)
		)
		(property "Footprint" ""
			(at 386.08 73.66 0)
			(effects
				(font
					(size 1.27 1.27)
				)
				(hide yes)
			)
		)
		(property "Datasheet" ""
			(at 386.08 73.66 0)
			(effects
				(font
					(size 1.27 1.27)
				)
				(hide yes)
			)
		)
		(property "Description" ""
			(at 386.08 73.66 0)
			(effects
				(font
					(size 1.27 1.27)
				)
				(hide yes)
			)
		)
		(property "Author" "Antmicro"
			(at 377.19 81.28 0)
			(effects
				(font
					(size 1.27 1.27)
					(thickness 0.15)
				)
				(justify left bottom)
				(hide yes)
			)
		)
		(property "License" "Apache-2.0"
			(at 377.19 83.82 0)
			(effects
				(font
					(size 1.27 1.27)
					(thickness 0.15)
				)
				(justify left bottom)
				(hide yes)
			)
		)
		(pin "1"
		)
		(instances
			(project "environment-sensor"
				(path ""
					(reference "#PWR075")
					(unit 1)
				)
			)
		)
	)
	(symbol
		(lib_id "antmicropower:GND")
		(at 50.8 106.68 0)
		(unit 1)
		(exclude_from_sim no)
		(in_bom yes)
		(on_board yes)
		(dnp no)
		(fields_autoplaced yes)
		(property "Reference" "#PWR05"
			(at 50.8 113.03 0)
			(effects
				(font
					(size 1.27 1.27)
				)
				(hide yes)
			)
		)
		(property "Value" "GND"
			(at 50.8 111.76 0)
			(effects
				(font
					(size 1.27 1.27)
				)
			)
		)
		(property "Footprint" ""
			(at 50.8 106.68 0)
			(effects
				(font
					(size 1.27 1.27)
				)
				(hide yes)
			)
		)
		(property "Datasheet" ""
			(at 50.8 106.68 0)
			(effects
				(font
					(size 1.27 1.27)
				)
				(hide yes)
			)
		)
		(property "Description" ""
			(at 50.8 106.68 0)
			(effects
				(font
					(size 1.27 1.27)
				)
				(hide yes)
			)
		)
		(property "Author" "Antmicro"
			(at 59.69 114.3 0)
			(effects
				(font
					(size 1.27 1.27)
					(thickness 0.15)
				)
				(justify left bottom)
				(hide yes)
			)
		)
		(property "License" "Apache-2.0"
			(at 59.69 116.84 0)
			(effects
				(font
					(size 1.27 1.27)
					(thickness 0.15)
				)
				(justify left bottom)
				(hide yes)
			)
		)
		(pin "1"
		)
		(instances
			(project "environment-sensor"
				(path ""
					(reference "#PWR05")
					(unit 1)
				)
			)
		)
	)
	(symbol
		(lib_id "antmicroCapacitors0402:C_100n_0402")
		(at 260.35 38.1 270)
		(mirror x)
		(unit 1)
		(exclude_from_sim no)
		(in_bom yes)
		(on_board yes)
		(dnp no)
		(fields_autoplaced yes)
		(property "Reference" "C18"
			(at 254 34.29 90)
			(effects
				(font
					(size 1.27 1.27)
					(thickness 0.15)
				)
				(justify left)
			)
		)
		(property "Value" "C_100n_0402"
			(at 250.19 17.78 0)
			(effects
				(font
					(size 1.27 1.27)
					(thickness 0.15)
				)
				(justify left bottom)
				(hide yes)
			)
		)
		(property "Footprint" "antmicro-footprints:C_0402_1005Metric"
			(at 247.65 17.78 0)
			(effects
				(font
					(size 1.27 1.27)
					(thickness 0.15)
				)
				(justify left bottom)
				(hide yes)
			)
		)
		(property "Datasheet" "https://www.murata.com/products/productdetail?partno=GRM155R61H104KE14%23"
			(at 245.11 17.78 0)
			(effects
				(font
					(size 1.27 1.27)
					(thickness 0.15)
				)
				(justify left bottom)
				(hide yes)
			)
		)
		(property "Description" "SMD Multilayer Ceramic Capacitor, 0.1 µF, 50 V, 0402 [1005 Metric], ± 10%, X5R, GRM Series"
			(at 260.35 38.1 0)
			(effects
				(font
					(size 1.27 1.27)
				)
				(hide yes)
			)
		)
		(property "Manufacturer" "Murata"
			(at 240.03 17.78 0)
			(effects
				(font
					(size 1.27 1.27)
					(thickness 0.15)
				)
				(justify left bottom)
				(hide yes)
			)
		)
		(property "MPN" "GRM155R61H104KE14D"
			(at 242.57 17.78 0)
			(effects
				(font
					(size 1.27 1.27)
					(thickness 0.15)
				)
				(justify left bottom)
				(hide yes)
			)
		)
		(property "Val" "100n"
			(at 254 36.83 90)
			(effects
				(font
					(size 1.27 1.27)
					(thickness 0.15)
				)
				(justify left)
			)
		)
		(property "License" "Apache-2.0"
			(at 237.49 17.78 0)
			(effects
				(font
					(size 1.27 1.27)
					(thickness 0.15)
				)
				(justify left bottom)
				(hide yes)
			)
		)
		(property "Author" "Antmicro"
			(at 234.95 17.78 0)
			(effects
				(font
					(size 1.27 1.27)
					(thickness 0.15)
				)
				(justify left bottom)
				(hide yes)
			)
		)
		(property "Voltage" "50V"
			(at 232.41 17.78 0)
			(effects
				(font
					(size 1.27 1.27)
				)
				(justify left bottom)
				(hide yes)
			)
		)
		(property "Dielectric" "X5R"
			(at 229.87 17.78 0)
			(effects
				(font
					(size 1.27 1.27)
				)
				(justify left bottom)
				(hide yes)
			)
		)
		(property "Public" "False"
			(at 227.33 17.78 0)
			(effects
				(font
					(size 1.27 1.27)
				)
				(justify left bottom)
				(hide yes)
			)
		)
		(pin "1"
		)
		(pin "2"
		)
		(instances
			(project "environment-sensor"
				(path ""
					(reference "C18")
					(unit 1)
				)
			)
		)
	)
	(symbol
		(lib_id "antmicroCapacitors0402:C_2u2_0402")
		(at 219.71 118.11 270)
		(mirror x)
		(unit 1)
		(exclude_from_sim no)
		(in_bom yes)
		(on_board yes)
		(dnp no)
		(fields_autoplaced yes)
		(property "Reference" "C20"
			(at 217.17 114.2935 90)
			(effects
				(font
					(size 1.27 1.27)
					(thickness 0.15)
				)
				(justify right)
			)
		)
		(property "Value" "C_2u2_0402"
			(at 209.55 97.79 0)
			(effects
				(font
					(size 1.27 1.27)
					(thickness 0.15)
				)
				(justify left bottom)
				(hide yes)
			)
		)
		(property "Footprint" "antmicro-footprints:C_0402_1005Metric"
			(at 207.01 97.79 0)
			(effects
				(font
					(size 1.27 1.27)
					(thickness 0.15)
				)
				(justify left bottom)
				(hide yes)
			)
		)
		(property "Datasheet" "https://product.tdk.com/en/search/capacitor/ceramic/mlcc/info?part_no=C1005X5R1A225K050BC"
			(at 204.47 97.79 0)
			(effects
				(font
					(size 1.27 1.27)
					(thickness 0.15)
				)
				(justify left bottom)
				(hide yes)
			)
		)
		(property "Description" "SMD Multilayer Ceramic Capacitor, 2.2 µF, 10 V, 0402 [1005 Metric], ± 10%, X5R, C"
			(at 219.71 118.11 0)
			(effects
				(font
					(size 1.27 1.27)
				)
				(hide yes)
			)
		)
		(property "Manufacturer" "TDK"
			(at 199.39 97.79 0)
			(effects
				(font
					(size 1.27 1.27)
					(thickness 0.15)
				)
				(justify left bottom)
				(hide yes)
			)
		)
		(property "MPN" "C1005X5R1A225K050BC"
			(at 201.93 97.79 0)
			(effects
				(font
					(size 1.27 1.27)
					(thickness 0.15)
				)
				(justify left bottom)
				(hide yes)
			)
		)
		(property "Val" "2u2"
			(at 217.17 116.8335 90)
			(effects
				(font
					(size 1.27 1.27)
					(thickness 0.15)
				)
				(justify right)
			)
		)
		(property "License" "Apache-2.0"
			(at 196.85 97.79 0)
			(effects
				(font
					(size 1.27 1.27)
					(thickness 0.15)
				)
				(justify left bottom)
				(hide yes)
			)
		)
		(property "Author" "Antmicro"
			(at 194.31 97.79 0)
			(effects
				(font
					(size 1.27 1.27)
					(thickness 0.15)
				)
				(justify left bottom)
				(hide yes)
			)
		)
		(property "Voltage" ""
			(at 191.77 97.79 0)
			(effects
				(font
					(size 1.27 1.27)
				)
				(justify left bottom)
				(hide yes)
			)
		)
		(property "Dielectric" ""
			(at 189.23 97.79 0)
			(effects
				(font
					(size 1.27 1.27)
				)
				(justify left bottom)
				(hide yes)
			)
		)
		(property "Public" "False"
			(at 186.69 97.79 0)
			(effects
				(font
					(size 1.27 1.27)
				)
				(justify left bottom)
				(hide yes)
			)
		)
		(pin "1"
		)
		(pin "2"
		)
		(instances
			(project "environment-sensor"
				(path ""
					(reference "C20")
					(unit 1)
				)
			)
		)
	)
	(symbol
		(lib_id "antmicropower:GND")
		(at 193.04 119.38 0)
		(mirror y)
		(unit 1)
		(exclude_from_sim no)
		(in_bom yes)
		(on_board yes)
		(dnp no)
		(fields_autoplaced yes)
		(property "Reference" "#PWR058"
			(at 193.04 125.73 0)
			(effects
				(font
					(size 1.27 1.27)
				)
				(hide yes)
			)
		)
		(property "Value" "GND"
			(at 193.04 124.46 0)
			(effects
				(font
					(size 1.27 1.27)
				)
			)
		)
		(property "Footprint" ""
			(at 193.04 119.38 0)
			(effects
				(font
					(size 1.27 1.27)
				)
				(hide yes)
			)
		)
		(property "Datasheet" ""
			(at 193.04 119.38 0)
			(effects
				(font
					(size 1.27 1.27)
				)
				(hide yes)
			)
		)
		(property "Description" ""
			(at 193.04 119.38 0)
			(effects
				(font
					(size 1.27 1.27)
				)
				(hide yes)
			)
		)
		(property "Author" "Antmicro"
			(at 184.15 127 0)
			(effects
				(font
					(size 1.27 1.27)
					(thickness 0.15)
				)
				(justify left bottom)
				(hide yes)
			)
		)
		(property "License" "Apache-2.0"
			(at 184.15 129.54 0)
			(effects
				(font
					(size 1.27 1.27)
					(thickness 0.15)
				)
				(justify left bottom)
				(hide yes)
			)
		)
		(pin "1"
		)
		(instances
			(project "environment-sensor"
				(path ""
					(reference "#PWR058")
					(unit 1)
				)
			)
		)
	)
	(symbol
		(lib_id "antmicroMechanicalParts:antmicro_logo")
		(at 163.83 280.67 0)
		(unit 1)
		(exclude_from_sim no)
		(in_bom no)
		(on_board yes)
		(dnp no)
		(fields_autoplaced yes)
		(property "Reference" "N1"
			(at 170.18 278.6862 0)
			(effects
				(font
					(size 1.27 1.27)
					(thickness 0.15)
				)
				(justify left)
			)
		)
		(property "Value" "antmicro_logo"
			(at 170.18 281.2262 0)
			(effects
				(font
					(size 1.27 1.27)
					(thickness 0.15)
				)
				(justify left)
			)
		)
		(property "Footprint" "antmicro-footprints:antmicro-logo_scaled_12mm"
			(at 179.07 290.83 0)
			(effects
				(font
					(size 1.27 1.27)
					(thickness 0.15)
				)
				(justify left bottom)
				(hide yes)
			)
		)
		(property "Datasheet" ""
			(at 179.07 293.37 0)
			(effects
				(font
					(size 1.27 1.27)
					(thickness 0.15)
				)
				(justify left bottom)
				(hide yes)
			)
		)
		(property "Description" "Mechanical part"
			(at 163.83 280.67 0)
			(effects
				(font
					(size 1.27 1.27)
				)
				(hide yes)
			)
		)
		(property "MPN" ""
			(at 163.83 280.67 0)
			(effects
				(font
					(size 1.27 1.27)
				)
				(hide yes)
			)
		)
		(property "Manufacturer" ""
			(at 179.07 300.99 0)
			(effects
				(font
					(size 1.27 1.27)
					(thickness 0.15)
				)
				(justify left bottom)
				(hide yes)
			)
		)
		(property "Author" "Antmicro"
			(at 179.07 295.91 0)
			(effects
				(font
					(size 1.27 1.27)
					(thickness 0.15)
				)
				(justify left bottom)
				(hide yes)
			)
		)
		(property "License" "Apache-2.0"
			(at 179.07 298.45 0)
			(effects
				(font
					(size 1.27 1.27)
					(thickness 0.15)
				)
				(justify left bottom)
				(hide yes)
			)
		)
		(property "Public" "False"
			(at 179.07 300.99 0)
			(effects
				(font
					(size 1.27 1.27)
				)
				(justify left bottom)
				(hide yes)
			)
		)
		(instances
			(project "environment-sensor"
				(path ""
					(reference "N1")
					(unit 1)
				)
			)
		)
	)
	(symbol
		(lib_id "antmicropower:GND")
		(at 231.14 119.38 0)
		(mirror y)
		(unit 1)
		(exclude_from_sim no)
		(in_bom yes)
		(on_board yes)
		(dnp no)
		(fields_autoplaced yes)
		(property "Reference" "#PWR043"
			(at 231.14 125.73 0)
			(effects
				(font
					(size 1.27 1.27)
				)
				(hide yes)
			)
		)
		(property "Value" "GND"
			(at 231.14 124.46 0)
			(effects
				(font
					(size 1.27 1.27)
				)
			)
		)
		(property "Footprint" ""
			(at 231.14 119.38 0)
			(effects
				(font
					(size 1.27 1.27)
				)
				(hide yes)
			)
		)
		(property "Datasheet" ""
			(at 231.14 119.38 0)
			(effects
				(font
					(size 1.27 1.27)
				)
				(hide yes)
			)
		)
		(property "Description" ""
			(at 231.14 119.38 0)
			(effects
				(font
					(size 1.27 1.27)
				)
				(hide yes)
			)
		)
		(property "Author" "Antmicro"
			(at 222.25 127 0)
			(effects
				(font
					(size 1.27 1.27)
					(thickness 0.15)
				)
				(justify left bottom)
				(hide yes)
			)
		)
		(property "License" "Apache-2.0"
			(at 222.25 129.54 0)
			(effects
				(font
					(size 1.27 1.27)
					(thickness 0.15)
				)
				(justify left bottom)
				(hide yes)
			)
		)
		(pin "1"
		)
		(instances
			(project "environment-sensor"
				(path ""
					(reference "#PWR043")
					(unit 1)
				)
			)
		)
	)
	(symbol
		(lib_id "antmicroWire2BoardConnectors:JST_SH_1x4_SM04B-SRSS-TB-LF-SN")
		(at 373.38 226.06 0)
		(mirror x)
		(unit 1)
		(exclude_from_sim no)
		(in_bom yes)
		(on_board yes)
		(dnp no)
		(fields_autoplaced yes)
		(property "Reference" "J3"
			(at 381 220.98 0)
			(effects
				(font
					(size 1.27 1.27)
					(thickness 0.15)
				)
				(justify left)
			)
		)
		(property "Value" "JST_SH_1x4_SM04B-SRSS-TB-LF-SN"
			(at 400.05 218.44 0)
			(effects
				(font
					(size 1.27 1.27)
					(thickness 0.15)
				)
				(justify left bottom)
				(hide yes)
			)
		)
		(property "Footprint" "antmicro-footprints:Conn_JST_SH_1x4_SM04B-SRSS-TB-LF-SN"
			(at 400.05 215.9 0)
			(effects
				(font
					(size 1.27 1.27)
					(thickness 0.15)
				)
				(justify left bottom)
				(hide yes)
			)
		)
		(property "Datasheet" "https://www.jst-mfg.com/product/pdf/eng/eSH.pdf"
			(at 400.05 213.36 0)
			(effects
				(font
					(size 1.27 1.27)
					(thickness 0.15)
				)
				(justify left bottom)
				(hide yes)
			)
		)
		(property "Description" "Pin Header, Right Angle, Wire-to-Board, 1 mm, 1 Rows, 4 Contacts, Surface Mount Right Angle, SH"
			(at 373.38 226.06 0)
			(effects
				(font
					(size 1.27 1.27)
				)
				(hide yes)
			)
		)
		(property "MPN" "SM04B-SRSS-TB(LF)(SN)"
			(at 381 218.44 0)
			(effects
				(font
					(size 1.27 1.27)
					(thickness 0.15)
				)
				(justify left)
			)
		)
		(property "Manufacturer" "JST Automotive Connectors"
			(at 400.05 210.82 0)
			(effects
				(font
					(size 1.27 1.27)
					(thickness 0.15)
				)
				(justify left bottom)
				(hide yes)
			)
		)
		(property "Author" "Antmicro"
			(at 400.05 208.28 0)
			(effects
				(font
					(size 1.27 1.27)
					(thickness 0.15)
				)
				(justify left bottom)
				(hide yes)
			)
		)
		(property "License" "Apache-2.0"
			(at 400.05 205.74 0)
			(effects
				(font
					(size 1.27 1.27)
					(thickness 0.15)
				)
				(justify left bottom)
				(hide yes)
			)
		)
		(pin "MP"
		)
		(pin "1"
		)
		(pin "2"
		)
		(pin "4"
		)
		(pin "3"
		)
		(instances
			(project "environment-sensor"
				(path ""
					(reference "J3")
					(unit 1)
				)
			)
		)
	)
	(symbol
		(lib_id "antmicroFerriteBeadsandChips:FB_120Z_2A_Murata-BLM18PG_0603")
		(at 40.64 104.14 0)
		(unit 1)
		(exclude_from_sim no)
		(in_bom yes)
		(on_board yes)
		(dnp no)
		(fields_autoplaced yes)
		(property "Reference" "FB1"
			(at 43.1419 97.79 0)
			(effects
				(font
					(size 1.27 1.27)
					(thickness 0.15)
				)
			)
		)
		(property "Value" "FB_120Z_2A_Murata-BLM18PG_0603"
			(at 55.88 106.68 0)
			(effects
				(font
					(size 1.27 1.27)
					(thickness 0.15)
				)
				(justify left bottom)
				(hide yes)
			)
		)
		(property "Footprint" "antmicro-footprints:FB_0603_1608Metric"
			(at 55.88 111.76 0)
			(effects
				(font
					(size 1.27 1.27)
					(thickness 0.15)
				)
				(justify left bottom)
				(hide yes)
			)
		)
		(property "Datasheet" "https://www.murata.com/en-us/products/productdata/8796738650142/ENFA0003.pdf"
			(at 55.88 114.3 0)
			(effects
				(font
					(size 1.27 1.27)
					(thickness 0.15)
				)
				(justify left bottom)
				(hide yes)
			)
		)
		(property "Description" "Ferrite Bead, 0603 [1608 Metric], 120 ohm, 2 A, BLM18P, 0.05 ohm, ± 25%, DC power line"
			(at 40.64 104.14 0)
			(effects
				(font
					(size 1.27 1.27)
				)
				(hide yes)
			)
		)
		(property "Val" "120Z/2A"
			(at 43.1419 100.33 0)
			(effects
				(font
					(size 1.27 1.27)
				)
			)
		)
		(property "MPN" "BLM18PG121SN1D"
			(at 55.88 116.84 0)
			(effects
				(font
					(size 1.27 1.27)
					(thickness 0.15)
				)
				(justify left bottom)
				(hide yes)
			)
		)
		(property "Manufacturer" "Murata"
			(at 55.88 119.38 0)
			(effects
				(font
					(size 1.27 1.27)
					(thickness 0.15)
				)
				(justify left bottom)
				(hide yes)
			)
		)
		(property "Current" ""
			(at 60.96 127 0)
			(effects
				(font
					(size 1.27 1.27)
					(thickness 0.15)
				)
				(justify left bottom)
				(hide yes)
			)
		)
		(property "Author" "Antmicro"
			(at 55.88 121.92 0)
			(effects
				(font
					(size 1.27 1.27)
					(thickness 0.15)
				)
				(justify left bottom)
				(hide yes)
			)
		)
		(property "License" "Apache-2.0"
			(at 55.88 124.46 0)
			(effects
				(font
					(size 1.27 1.27)
					(thickness 0.15)
				)
				(justify left bottom)
				(hide yes)
			)
		)
		(property "Public" "False"
			(at 60.96 119.38 0)
			(effects
				(font
					(size 1.27 1.27)
				)
				(justify left bottom)
				(hide yes)
			)
		)
		(pin "2"
		)
		(pin "1"
		)
		(instances
			(project "environment-sensor"
				(path ""
					(reference "FB1")
					(unit 1)
				)
			)
		)
	)
	(symbol
		(lib_id "antmicropower:GND")
		(at 161.29 73.66 0)
		(unit 1)
		(exclude_from_sim no)
		(in_bom yes)
		(on_board yes)
		(dnp no)
		(fields_autoplaced yes)
		(property "Reference" "#PWR021"
			(at 161.29 80.01 0)
			(effects
				(font
					(size 1.27 1.27)
				)
				(hide yes)
			)
		)
		(property "Value" "GND"
			(at 161.29 78.74 0)
			(effects
				(font
					(size 1.27 1.27)
				)
			)
		)
		(property "Footprint" ""
			(at 161.29 73.66 0)
			(effects
				(font
					(size 1.27 1.27)
				)
				(hide yes)
			)
		)
		(property "Datasheet" ""
			(at 161.29 73.66 0)
			(effects
				(font
					(size 1.27 1.27)
				)
				(hide yes)
			)
		)
		(property "Description" ""
			(at 161.29 73.66 0)
			(effects
				(font
					(size 1.27 1.27)
				)
				(hide yes)
			)
		)
		(property "Author" "Antmicro"
			(at 170.18 81.28 0)
			(effects
				(font
					(size 1.27 1.27)
					(thickness 0.15)
				)
				(justify left bottom)
				(hide yes)
			)
		)
		(property "License" "Apache-2.0"
			(at 170.18 83.82 0)
			(effects
				(font
					(size 1.27 1.27)
					(thickness 0.15)
				)
				(justify left bottom)
				(hide yes)
			)
		)
		(pin "1"
		)
		(instances
			(project "environment-sensor"
				(path ""
					(reference "#PWR021")
					(unit 1)
				)
			)
		)
	)
	(symbol
		(lib_id "antmicropower:GND")
		(at 107.95 171.45 0)
		(unit 1)
		(exclude_from_sim no)
		(in_bom yes)
		(on_board yes)
		(dnp no)
		(fields_autoplaced yes)
		(property "Reference" "#PWR016"
			(at 107.95 177.8 0)
			(effects
				(font
					(size 1.27 1.27)
				)
				(hide yes)
			)
		)
		(property "Value" "GND"
			(at 111.125 173.99 0)
			(effects
				(font
					(size 1.27 1.27)
				)
			)
		)
		(property "Footprint" ""
			(at 107.95 171.45 0)
			(effects
				(font
					(size 1.27 1.27)
				)
				(hide yes)
			)
		)
		(property "Datasheet" ""
			(at 107.95 171.45 0)
			(effects
				(font
					(size 1.27 1.27)
				)
				(hide yes)
			)
		)
		(property "Description" ""
			(at 107.95 171.45 0)
			(effects
				(font
					(size 1.27 1.27)
				)
				(hide yes)
			)
		)
		(property "Author" "Antmicro"
			(at 116.84 179.07 0)
			(effects
				(font
					(size 1.27 1.27)
					(thickness 0.15)
				)
				(justify left bottom)
				(hide yes)
			)
		)
		(property "License" "Apache-2.0"
			(at 116.84 181.61 0)
			(effects
				(font
					(size 1.27 1.27)
					(thickness 0.15)
				)
				(justify left bottom)
				(hide yes)
			)
		)
		(pin "1"
		)
		(instances
			(project "environment-sensor"
				(path ""
					(reference "#PWR016")
					(unit 1)
				)
			)
		)
	)
	(symbol
		(lib_id "antmicroTestPoints:TP_1.5mm_SMD")
		(at 147.32 242.57 180)
		(unit 1)
		(exclude_from_sim no)
		(in_bom yes)
		(on_board yes)
		(dnp no)
		(fields_autoplaced yes)
		(property "Reference" "TP1"
			(at 140.335 241.3 0)
			(effects
				(font
					(size 1.27 1.27)
					(thickness 0.15)
				)
			)
		)
		(property "Value" "TP_1.5mm_SMD"
			(at 132.08 234.95 0)
			(effects
				(font
					(size 1.27 1.27)
					(thickness 0.15)
				)
				(justify left bottom)
				(hide yes)
			)
		)
		(property "Footprint" "antmicro-footprints:TP_SMD_1.5mm"
			(at 132.08 232.41 0)
			(effects
				(font
					(size 1.27 1.27)
					(thickness 0.15)
				)
				(justify left bottom)
				(hide yes)
			)
		)
		(property "Datasheet" ""
			(at 132.08 229.87 0)
			(effects
				(font
					(size 1.27 1.27)
					(thickness 0.15)
				)
				(justify left bottom)
				(hide yes)
			)
		)
		(property "Description" "test point, SMT"
			(at 147.32 242.57 0)
			(effects
				(font
					(size 1.27 1.27)
				)
				(hide yes)
			)
		)
		(property "MPN" ""
			(at 147.32 242.57 0)
			(effects
				(font
					(size 1.27 1.27)
				)
				(hide yes)
			)
		)
		(property "Manufacturer" ""
			(at 147.32 242.57 0)
			(effects
				(font
					(size 1.27 1.27)
				)
				(hide yes)
			)
		)
		(property "Author" "Antmicro"
			(at 132.08 227.33 0)
			(effects
				(font
					(size 1.27 1.27)
					(thickness 0.15)
				)
				(justify left bottom)
				(hide yes)
			)
		)
		(property "License" "Apache-2.0"
			(at 132.08 224.79 0)
			(effects
				(font
					(size 1.27 1.27)
					(thickness 0.15)
				)
				(justify left bottom)
				(hide yes)
			)
		)
		(property "Public" "False"
			(at 132.08 222.25 0)
			(effects
				(font
					(size 1.27 1.27)
				)
				(justify left bottom)
				(hide yes)
			)
		)
		(pin "1"
		)
		(instances
			(project "environment-sensor"
				(path ""
					(reference "TP1")
					(unit 1)
				)
			)
		)
	)
	(symbol
		(lib_id "antmicropower:GND")
		(at 264.16 118.11 0)
		(mirror y)
		(unit 1)
		(exclude_from_sim no)
		(in_bom yes)
		(on_board yes)
		(dnp no)
		(fields_autoplaced yes)
		(property "Reference" "#PWR037"
			(at 264.16 124.46 0)
			(effects
				(font
					(size 1.27 1.27)
				)
				(hide yes)
			)
		)
		(property "Value" "GND"
			(at 264.16 123.19 0)
			(effects
				(font
					(size 1.27 1.27)
				)
			)
		)
		(property "Footprint" ""
			(at 264.16 118.11 0)
			(effects
				(font
					(size 1.27 1.27)
				)
				(hide yes)
			)
		)
		(property "Datasheet" ""
			(at 264.16 118.11 0)
			(effects
				(font
					(size 1.27 1.27)
				)
				(hide yes)
			)
		)
		(property "Description" ""
			(at 264.16 118.11 0)
			(effects
				(font
					(size 1.27 1.27)
				)
				(hide yes)
			)
		)
		(property "Author" "Antmicro"
			(at 255.27 125.73 0)
			(effects
				(font
					(size 1.27 1.27)
					(thickness 0.15)
				)
				(justify left bottom)
				(hide yes)
			)
		)
		(property "License" "Apache-2.0"
			(at 255.27 128.27 0)
			(effects
				(font
					(size 1.27 1.27)
					(thickness 0.15)
				)
				(justify left bottom)
				(hide yes)
			)
		)
		(pin "1"
		)
		(instances
			(project "environment-sensor"
				(path ""
					(reference "#PWR037")
					(unit 1)
				)
			)
		)
	)
	(symbol
		(lib_id "antmicroResonators:Resonator_8MHz_ABM3B")
		(at 289.56 191.77 0)
		(unit 1)
		(exclude_from_sim no)
		(in_bom yes)
		(on_board yes)
		(dnp no)
		(fields_autoplaced yes)
		(property "Reference" "Y2"
			(at 293.37 184.15 0)
			(effects
				(font
					(size 1.27 1.27)
					(thickness 0.15)
				)
			)
		)
		(property "Value" "Resonator_8MHz_ABM3B"
			(at 304.8 204.47 0)
			(effects
				(font
					(size 1.27 1.27)
					(thickness 0.15)
				)
				(justify left bottom)
				(hide yes)
			)
		)
		(property "Footprint" "antmicro-footprints:Resonator_SMD_Abracon_ABM3B_5x3.2mm"
			(at 304.8 207.01 0)
			(effects
				(font
					(size 1.27 1.27)
					(thickness 0.15)
				)
				(justify left bottom)
				(hide yes)
			)
		)
		(property "Datasheet" "https://abracon.com/Resonators/abm3b.pdf"
			(at 304.8 209.55 0)
			(effects
				(font
					(size 1.27 1.27)
					(thickness 0.15)
				)
				(justify left bottom)
				(hide yes)
			)
		)
		(property "Description" "Crystal, 8 MHz, SMT, 5mm x 3.2mm, 10 ppm, 10 pF, 10 ppm"
			(at 289.56 191.77 0)
			(effects
				(font
					(size 1.27 1.27)
				)
				(hide yes)
			)
		)
		(property "MPN" "ABM3B-8.000MHZ-10-1-U-T"
			(at 304.8 199.39 0)
			(effects
				(font
					(size 1.27 1.27)
					(thickness 0.15)
				)
				(justify left bottom)
				(hide yes)
			)
		)
		(property "Manufacturer" "Abracon"
			(at 304.8 212.09 0)
			(effects
				(font
					(size 1.27 1.27)
					(thickness 0.15)
				)
				(justify left bottom)
				(hide yes)
			)
		)
		(property "Author" "Antmicro"
			(at 304.8 214.63 0)
			(effects
				(font
					(size 1.27 1.27)
					(thickness 0.15)
				)
				(justify left bottom)
				(hide yes)
			)
		)
		(property "License" "Apache-2.0"
			(at 304.8 217.17 0)
			(effects
				(font
					(size 1.27 1.27)
					(thickness 0.15)
				)
				(justify left bottom)
				(hide yes)
			)
		)
		(property "Val" "8 MHz"
			(at 293.37 186.69 0)
			(effects
				(font
					(size 1.27 1.27)
					(thickness 0.15)
				)
			)
		)
		(property "Public" "False"
			(at 312.42 217.17 0)
			(effects
				(font
					(size 1.27 1.27)
				)
				(justify left bottom)
				(hide yes)
			)
		)
		(pin "2"
		)
		(pin "4"
		)
		(pin "3"
		)
		(pin "1"
		)
		(instances
			(project "environment-sensor"
				(path ""
					(reference "Y2")
					(unit 1)
				)
			)
		)
	)
	(symbol
		(lib_id "antmicropower:GND")
		(at 78.74 115.57 0)
		(unit 1)
		(exclude_from_sim no)
		(in_bom yes)
		(on_board yes)
		(dnp no)
		(fields_autoplaced yes)
		(property "Reference" "#PWR011"
			(at 78.74 121.92 0)
			(effects
				(font
					(size 1.27 1.27)
				)
				(hide yes)
			)
		)
		(property "Value" "GND"
			(at 78.74 120.65 0)
			(effects
				(font
					(size 1.27 1.27)
				)
			)
		)
		(property "Footprint" ""
			(at 78.74 115.57 0)
			(effects
				(font
					(size 1.27 1.27)
				)
				(hide yes)
			)
		)
		(property "Datasheet" ""
			(at 78.74 115.57 0)
			(effects
				(font
					(size 1.27 1.27)
				)
				(hide yes)
			)
		)
		(property "Description" ""
			(at 78.74 115.57 0)
			(effects
				(font
					(size 1.27 1.27)
				)
				(hide yes)
			)
		)
		(property "Author" "Antmicro"
			(at 87.63 123.19 0)
			(effects
				(font
					(size 1.27 1.27)
					(thickness 0.15)
				)
				(justify left bottom)
				(hide yes)
			)
		)
		(property "License" "Apache-2.0"
			(at 87.63 125.73 0)
			(effects
				(font
					(size 1.27 1.27)
					(thickness 0.15)
				)
				(justify left bottom)
				(hide yes)
			)
		)
		(pin "1"
		)
		(instances
			(project "environment-sensor"
				(path ""
					(reference "#PWR011")
					(unit 1)
				)
			)
		)
	)
	(symbol
		(lib_id "antmicroResistors0402:R_100k_0402")
		(at 316.23 45.72 270)
		(mirror x)
		(unit 1)
		(exclude_from_sim no)
		(in_bom no)
		(on_board yes)
		(dnp yes)
		(fields_autoplaced yes)
		(property "Reference" "R33"
			(at 318.77 41.9099 90)
			(effects
				(font
					(size 1.27 1.27)
					(thickness 0.15)
				)
				(justify left)
			)
		)
		(property "Value" "R_100k_0402"
			(at 303.53 25.4 0)
			(effects
				(font
					(size 1.27 1.27)
					(thickness 0.15)
				)
				(justify left bottom)
				(hide yes)
			)
		)
		(property "Footprint" "antmicro-footprints:R_0402_1005Metric"
			(at 300.99 25.4 0)
			(effects
				(font
					(size 1.27 1.27)
					(thickness 0.15)
				)
				(justify left bottom)
				(hide yes)
			)
		)
		(property "Datasheet" "https://www.bourns.com/docs/product-datasheets/cr.pdf"
			(at 298.45 25.4 0)
			(effects
				(font
					(size 1.27 1.27)
					(thickness 0.15)
				)
				(justify left bottom)
				(hide yes)
			)
		)
		(property "Description" "SMD Chip Resistor, 100 kohm, ± 1%, 62.5 mW, 0402 [1005 Metric], Thick Film, General Purpose"
			(at 316.23 45.72 0)
			(effects
				(font
					(size 1.27 1.27)
				)
				(hide yes)
			)
		)
		(property "Manufacturer" "Bourns"
			(at 293.37 25.4 0)
			(effects
				(font
					(size 1.27 1.27)
					(thickness 0.15)
				)
				(justify left bottom)
				(hide yes)
			)
		)
		(property "MPN" "CR0402-FX-1003GLF"
			(at 295.91 25.4 0)
			(effects
				(font
					(size 1.27 1.27)
					(thickness 0.15)
				)
				(justify left bottom)
				(hide yes)
			)
		)
		(property "Val" "100k"
			(at 318.77 44.4499 90)
			(effects
				(font
					(size 1.27 1.27)
					(thickness 0.15)
				)
				(justify left)
			)
		)
		(property "License" "Apache-2.0"
			(at 290.83 25.4 0)
			(effects
				(font
					(size 1.27 1.27)
					(thickness 0.15)
				)
				(justify left bottom)
				(hide yes)
			)
		)
		(property "Author" "Antmicro"
			(at 288.29 25.4 0)
			(effects
				(font
					(size 1.27 1.27)
					(thickness 0.15)
				)
				(justify left bottom)
				(hide yes)
			)
		)
		(property "Tolerance" "1%"
			(at 306.07 25.4 0)
			(effects
				(font
					(size 1.27 1.27)
				)
				(justify left bottom)
				(hide yes)
			)
		)
		(property "Public" "False"
			(at 285.75 25.4 0)
			(effects
				(font
					(size 1.27 1.27)
				)
				(justify left bottom)
				(hide yes)
			)
		)
		(pin "1"
		)
		(pin "2"
		)
		(instances
			(project "environment-sensor"
				(path ""
					(reference "R33")
					(unit 1)
				)
			)
		)
	)
	(symbol
		(lib_id "antmicroTestPoints:TP_1mm_SMD")
		(at 370.84 73.66 90)
		(mirror x)
		(unit 1)
		(exclude_from_sim no)
		(in_bom yes)
		(on_board yes)
		(dnp no)
		(fields_autoplaced yes)
		(property "Reference" "TP9"
			(at 372.11 77.47 90)
			(effects
				(font
					(size 1.27 1.27)
					(thickness 0.15)
				)
				(justify right)
			)
		)
		(property "Value" "TP_1mm_SMD"
			(at 368.3 78.1049 90)
			(effects
				(font
					(size 1.27 1.27)
					(thickness 0.15)
				)
				(justify left)
				(hide yes)
			)
		)
		(property "Footprint" "antmicro-footprints:TP_SMD_1mm"
			(at 381 88.9 0)
			(effects
				(font
					(size 1.27 1.27)
					(thickness 0.15)
				)
				(justify left bottom)
				(hide yes)
			)
		)
		(property "Datasheet" ""
			(at 383.54 88.9 0)
			(effects
				(font
					(size 1.27 1.27)
					(thickness 0.15)
				)
				(justify left bottom)
				(hide yes)
			)
		)
		(property "Description" "Test point 1mm SMD"
			(at 370.84 73.66 0)
			(effects
				(font
					(size 1.27 1.27)
				)
				(hide yes)
			)
		)
		(property "Author" "Antmicro"
			(at 386.08 88.9 0)
			(effects
				(font
					(size 1.27 1.27)
					(thickness 0.15)
				)
				(justify left bottom)
				(hide yes)
			)
		)
		(property "License" "Apache-2.0"
			(at 388.62 88.9 0)
			(effects
				(font
					(size 1.27 1.27)
					(thickness 0.15)
				)
				(justify left bottom)
				(hide yes)
			)
		)
		(property "MPN" ""
			(at 370.84 73.66 0)
			(effects
				(font
					(size 1.27 1.27)
				)
				(hide yes)
			)
		)
		(property "Manufacturer" ""
			(at 370.84 73.66 0)
			(effects
				(font
					(size 1.27 1.27)
				)
				(hide yes)
			)
		)
		(property "Public" "False"
			(at 391.16 88.9 0)
			(effects
				(font
					(size 1.27 1.27)
				)
				(justify left bottom)
				(hide yes)
			)
		)
		(pin "1"
		)
		(instances
			(project "environment-sensor"
				(path ""
					(reference "TP9")
					(unit 1)
				)
			)
		)
	)
	(symbol
		(lib_id "antmicroTVSDiodes:TPD2E009_SOT-9X3")
		(at 345.44 224.79 270)
		(unit 1)
		(exclude_from_sim no)
		(in_bom yes)
		(on_board yes)
		(dnp no)
		(fields_autoplaced yes)
		(property "Reference" "D8"
			(at 341.63 236.22 90)
			(effects
				(font
					(size 1.27 1.27)
					(thickness 0.15)
				)
				(justify left)
			)
		)
		(property "Value" "TPD2E009_SOT-9X3"
			(at 332.74 238.76 90)
			(effects
				(font
					(size 1.27 1.27)
					(thickness 0.15)
				)
				(justify left)
			)
		)
		(property "Footprint" "antmicro-footprints:SOT-723"
			(at 340.36 240.03 0)
			(effects
				(font
					(size 1.27 1.27)
					(thickness 0.15)
				)
				(justify left bottom)
				(hide yes)
			)
		)
		(property "Datasheet" "https://www.ti.com/lit/ds/symlink/tpd2e009.pdf?ts=1597910439511&ref_url=https%253A%252F%252Fwww.google.com%252F"
			(at 337.82 240.03 0)
			(effects
				(font
					(size 1.27 1.27)
					(thickness 0.15)
				)
				(justify left bottom)
				(hide yes)
			)
		)
		(property "Description" "TVS diode array, 8 kV, SOT-723, 5.5 V, 0.9 pF"
			(at 345.44 224.79 0)
			(effects
				(font
					(size 1.27 1.27)
				)
				(hide yes)
			)
		)
		(property "MPN" "TPD2E009DRTR"
			(at 335.28 240.03 0)
			(effects
				(font
					(size 1.27 1.27)
					(thickness 0.15)
				)
				(justify left bottom)
				(hide yes)
			)
		)
		(property "Manufacturer" "Texas Instruments"
			(at 332.74 240.03 0)
			(effects
				(font
					(size 1.27 1.27)
					(thickness 0.15)
				)
				(justify left bottom)
				(hide yes)
			)
		)
		(property "Author" "Antmicro"
			(at 330.2 240.03 0)
			(effects
				(font
					(size 1.27 1.27)
					(thickness 0.15)
				)
				(justify left bottom)
				(hide yes)
			)
		)
		(property "License" "Apache-2.0"
			(at 327.66 240.03 0)
			(effects
				(font
					(size 1.27 1.27)
					(thickness 0.15)
				)
				(justify left bottom)
				(hide yes)
			)
		)
		(pin "1"
		)
		(pin "2"
		)
		(pin "3"
		)
		(instances
			(project "environment-sensor"
				(path ""
					(reference "D8")
					(unit 1)
				)
			)
		)
	)
	(symbol
		(lib_id "antmicropower:PWR_FLAG")
		(at 224.79 31.75 0)
		(unit 1)
		(exclude_from_sim no)
		(in_bom yes)
		(on_board yes)
		(dnp no)
		(fields_autoplaced yes)
		(property "Reference" "#FLG02"
			(at 224.79 29.845 0)
			(effects
				(font
					(size 1.27 1.27)
				)
				(hide yes)
			)
		)
		(property "Value" "PWR_FLAG"
			(at 224.79 26.67 0)
			(effects
				(font
					(size 1.27 1.27)
				)
			)
		)
		(property "Footprint" ""
			(at 224.79 31.75 0)
			(effects
				(font
					(size 1.27 1.27)
				)
				(hide yes)
			)
		)
		(property "Datasheet" ""
			(at 224.79 31.75 0)
			(effects
				(font
					(size 1.27 1.27)
				)
				(hide yes)
			)
		)
		(property "Description" ""
			(at 224.79 31.75 0)
			(effects
				(font
					(size 1.27 1.27)
				)
				(hide yes)
			)
		)
		(pin "1"
		)
		(instances
			(project "environment-sensor"
				(path ""
					(reference "#FLG02")
					(unit 1)
				)
			)
		)
	)
	(symbol
		(lib_id "antmicroResonators:Resonator_32.768kHz_ECX-31B")
		(at 208.28 198.12 0)
		(unit 1)
		(exclude_from_sim no)
		(in_bom yes)
		(on_board yes)
		(dnp no)
		(fields_autoplaced yes)
		(property "Reference" "Y1"
			(at 212.09 191.77 0)
			(effects
				(font
					(size 1.27 1.27)
					(thickness 0.15)
				)
			)
		)
		(property "Value" "Resonator_32.768kHz_ECX-31B"
			(at 223.52 213.36 0)
			(effects
				(font
					(size 1.27 1.27)
					(thickness 0.15)
				)
				(justify left bottom)
				(hide yes)
			)
		)
		(property "Footprint" "antmicro-footprints:Resonator_SMD_ECS_ECX-31B_3.2x1.5x0.9mm"
			(at 223.52 215.9 0)
			(effects
				(font
					(size 1.27 1.27)
					(thickness 0.15)
				)
				(justify left bottom)
				(hide yes)
			)
		)
		(property "Datasheet" "http://www.ecsxtal.com/store/pdf/ecx-31b.pdf"
			(at 223.52 218.44 0)
			(effects
				(font
					(size 1.27 1.27)
					(thickness 0.15)
				)
				(justify left bottom)
				(hide yes)
			)
		)
		(property "Description" "Crystal, 32.768 kHz, SMT, 3.2mm x 1.5mm, 12.5 pF, 20 ppm, ECX-31B"
			(at 208.28 198.12 0)
			(effects
				(font
					(size 1.27 1.27)
				)
				(hide yes)
			)
		)
		(property "MPN" "ECS-.327-12.5-34B-TR"
			(at 223.52 205.74 0)
			(effects
				(font
					(size 1.27 1.27)
					(thickness 0.15)
				)
				(justify left bottom)
				(hide yes)
			)
		)
		(property "Manufacturer" "ECS Inc. International"
			(at 223.52 208.28 0)
			(effects
				(font
					(size 1.27 1.27)
					(thickness 0.15)
				)
				(justify left bottom)
				(hide yes)
			)
		)
		(property "Val" "32.768 kHz"
			(at 212.09 194.31 0)
			(effects
				(font
					(size 1.27 1.27)
					(thickness 0.15)
				)
			)
		)
		(property "Author" "Antmicro"
			(at 223.52 220.98 0)
			(effects
				(font
					(size 1.27 1.27)
					(thickness 0.15)
				)
				(justify left bottom)
				(hide yes)
			)
		)
		(property "License" "Apache-2.0"
			(at 223.52 223.52 0)
			(effects
				(font
					(size 1.27 1.27)
					(thickness 0.15)
				)
				(justify left bottom)
				(hide yes)
			)
		)
		(property "Public" "False"
			(at 231.14 223.52 0)
			(effects
				(font
					(size 1.27 1.27)
				)
				(justify left bottom)
				(hide yes)
			)
		)
		(pin "2"
		)
		(pin "1"
		)
		(instances
			(project "environment-sensor"
				(path ""
					(reference "Y1")
					(unit 1)
				)
			)
		)
	)
	(symbol
		(lib_id "antmicroResistors0402:R_1M_0402")
		(at 290.83 204.47 0)
		(unit 1)
		(exclude_from_sim no)
		(in_bom no)
		(on_board yes)
		(dnp yes)
		(fields_autoplaced yes)
		(property "Reference" "R25"
			(at 281.94 204.47 0)
			(effects
				(font
					(size 1.27 1.27)
					(thickness 0.15)
				)
				(justify left bottom)
			)
		)
		(property "Value" "R_1M_0402"
			(at 311.15 217.17 0)
			(effects
				(font
					(size 1.27 1.27)
					(thickness 0.15)
				)
				(justify left bottom)
				(hide yes)
			)
		)
		(property "Footprint" "antmicro-footprints:R_0402_1005Metric"
			(at 311.15 219.71 0)
			(effects
				(font
					(size 1.27 1.27)
					(thickness 0.15)
				)
				(justify left bottom)
				(hide yes)
			)
		)
		(property "Datasheet" "https://www.bourns.com/docs/product-datasheets/cr.pdf"
			(at 311.15 222.25 0)
			(effects
				(font
					(size 1.27 1.27)
					(thickness 0.15)
				)
				(justify left bottom)
				(hide yes)
			)
		)
		(property "Description" "SMD Chip Resistor, 1 Mohm, ± 1%, 62.5 mW, 0402 [1005 Metric], Thick Film, General Purpose"
			(at 290.83 204.47 0)
			(effects
				(font
					(size 1.27 1.27)
				)
				(hide yes)
			)
		)
		(property "Manufacturer" "Bourns"
			(at 311.15 227.33 0)
			(effects
				(font
					(size 1.27 1.27)
					(thickness 0.15)
				)
				(justify left bottom)
				(hide yes)
			)
		)
		(property "MPN" "CR0402-FX-1004GLF"
			(at 311.15 224.79 0)
			(effects
				(font
					(size 1.27 1.27)
					(thickness 0.15)
				)
				(justify left bottom)
				(hide yes)
			)
		)
		(property "Val" "1M"
			(at 283.21 207.01 0)
			(effects
				(font
					(size 1.27 1.27)
					(thickness 0.15)
				)
				(justify left bottom)
			)
		)
		(property "License" "Apache-2.0"
			(at 311.15 229.87 0)
			(effects
				(font
					(size 1.27 1.27)
					(thickness 0.15)
				)
				(justify left bottom)
				(hide yes)
			)
		)
		(property "Author" "Antmicro"
			(at 311.15 232.41 0)
			(effects
				(font
					(size 1.27 1.27)
					(thickness 0.15)
				)
				(justify left bottom)
				(hide yes)
			)
		)
		(property "Tolerance" "1%"
			(at 311.15 214.63 0)
			(effects
				(font
					(size 1.27 1.27)
				)
				(justify left bottom)
				(hide yes)
			)
		)
		(property "Public" "False"
			(at 311.15 234.95 0)
			(effects
				(font
					(size 1.27 1.27)
				)
				(justify left bottom)
				(hide yes)
			)
		)
		(pin "1"
		)
		(pin "2"
		)
		(instances
			(project "environment-sensor"
				(path ""
					(reference "R25")
					(unit 1)
				)
			)
		)
	)
	(symbol
		(lib_id "antmicroTestPoints:TP_1mm_SMD")
		(at 391.16 50.8 0)
		(unit 1)
		(exclude_from_sim no)
		(in_bom yes)
		(on_board yes)
		(dnp no)
		(fields_autoplaced yes)
		(property "Reference" "TP11"
			(at 396.24 50.7999 0)
			(effects
				(font
					(size 1.27 1.27)
					(thickness 0.15)
				)
				(justify left)
			)
		)
		(property "Value" "TP_1mm_SMD"
			(at 396.24 52.0699 0)
			(effects
				(font
					(size 1.27 1.27)
					(thickness 0.15)
				)
				(justify left)
				(hide yes)
			)
		)
		(property "Footprint" "antmicro-footprints:TP_SMD_1mm"
			(at 406.4 60.96 0)
			(effects
				(font
					(size 1.27 1.27)
					(thickness 0.15)
				)
				(justify left bottom)
				(hide yes)
			)
		)
		(property "Datasheet" ""
			(at 406.4 63.5 0)
			(effects
				(font
					(size 1.27 1.27)
					(thickness 0.15)
				)
				(justify left bottom)
				(hide yes)
			)
		)
		(property "Description" "Test point 1mm SMD"
			(at 391.16 50.8 0)
			(effects
				(font
					(size 1.27 1.27)
				)
				(hide yes)
			)
		)
		(property "Author" "Antmicro"
			(at 406.4 66.04 0)
			(effects
				(font
					(size 1.27 1.27)
					(thickness 0.15)
				)
				(justify left bottom)
				(hide yes)
			)
		)
		(property "License" "Apache-2.0"
			(at 406.4 68.58 0)
			(effects
				(font
					(size 1.27 1.27)
					(thickness 0.15)
				)
				(justify left bottom)
				(hide yes)
			)
		)
		(property "MPN" ""
			(at 391.16 50.8 0)
			(effects
				(font
					(size 1.27 1.27)
				)
				(hide yes)
			)
		)
		(property "Manufacturer" ""
			(at 391.16 50.8 0)
			(effects
				(font
					(size 1.27 1.27)
				)
				(hide yes)
			)
		)
		(property "Public" "False"
			(at 406.4 71.12 0)
			(effects
				(font
					(size 1.27 1.27)
				)
				(justify left bottom)
				(hide yes)
			)
		)
		(pin "1"
		)
		(instances
			(project "environment-sensor"
				(path ""
					(reference "TP11")
					(unit 1)
				)
			)
		)
	)
	(symbol
		(lib_id "antmicroResistors0402:R_100k_0402")
		(at 336.55 179.07 90)
		(unit 1)
		(exclude_from_sim no)
		(in_bom yes)
		(on_board yes)
		(dnp no)
		(fields_autoplaced yes)
		(property "Reference" "R36"
			(at 334.01 175.2599 90)
			(effects
				(font
					(size 1.27 1.27)
					(thickness 0.15)
				)
				(justify left)
			)
		)
		(property "Value" "R_100k_0402"
			(at 349.25 158.75 0)
			(effects
				(font
					(size 1.27 1.27)
					(thickness 0.15)
				)
				(justify left bottom)
				(hide yes)
			)
		)
		(property "Footprint" "antmicro-footprints:R_0402_1005Metric"
			(at 351.79 158.75 0)
			(effects
				(font
					(size 1.27 1.27)
					(thickness 0.15)
				)
				(justify left bottom)
				(hide yes)
			)
		)
		(property "Datasheet" "https://www.bourns.com/docs/product-datasheets/cr.pdf"
			(at 354.33 158.75 0)
			(effects
				(font
					(size 1.27 1.27)
					(thickness 0.15)
				)
				(justify left bottom)
				(hide yes)
			)
		)
		(property "Description" "SMD Chip Resistor, 100 kohm, ± 1%, 62.5 mW, 0402 [1005 Metric], Thick Film, General Purpose"
			(at 336.55 179.07 0)
			(effects
				(font
					(size 1.27 1.27)
				)
				(hide yes)
			)
		)
		(property "Manufacturer" "Bourns"
			(at 359.41 158.75 0)
			(effects
				(font
					(size 1.27 1.27)
					(thickness 0.15)
				)
				(justify left bottom)
				(hide yes)
			)
		)
		(property "MPN" "CR0402-FX-1003GLF"
			(at 356.87 158.75 0)
			(effects
				(font
					(size 1.27 1.27)
					(thickness 0.15)
				)
				(justify left bottom)
				(hide yes)
			)
		)
		(property "Val" "100k"
			(at 334.01 177.7999 90)
			(effects
				(font
					(size 1.27 1.27)
					(thickness 0.15)
				)
				(justify left)
			)
		)
		(property "License" "Apache-2.0"
			(at 361.95 158.75 0)
			(effects
				(font
					(size 1.27 1.27)
					(thickness 0.15)
				)
				(justify left bottom)
				(hide yes)
			)
		)
		(property "Author" "Antmicro"
			(at 364.49 158.75 0)
			(effects
				(font
					(size 1.27 1.27)
					(thickness 0.15)
				)
				(justify left bottom)
				(hide yes)
			)
		)
		(property "Tolerance" "1%"
			(at 346.71 158.75 0)
			(effects
				(font
					(size 1.27 1.27)
				)
				(justify left bottom)
				(hide yes)
			)
		)
		(property "Public" "False"
			(at 367.03 158.75 0)
			(effects
				(font
					(size 1.27 1.27)
				)
				(justify left bottom)
				(hide yes)
			)
		)
		(pin "1"
		)
		(pin "2"
		)
		(instances
			(project "environment-sensor"
				(path ""
					(reference "R36")
					(unit 1)
				)
			)
		)
	)
	(symbol
		(lib_id "antmicroResistors0402:R_470R_0402")
		(at 135.89 68.58 90)
		(unit 1)
		(exclude_from_sim no)
		(in_bom yes)
		(on_board yes)
		(dnp no)
		(fields_autoplaced yes)
		(property "Reference" "R12"
			(at 133.35 64.7699 90)
			(effects
				(font
					(size 1.27 1.27)
					(thickness 0.15)
				)
				(justify left)
			)
		)
		(property "Value" "R_470R_0402"
			(at 148.59 48.26 0)
			(effects
				(font
					(size 1.27 1.27)
					(thickness 0.15)
				)
				(justify left bottom)
				(hide yes)
			)
		)
		(property "Footprint" "antmicro-footprints:R_0402_1005Metric"
			(at 151.13 48.26 0)
			(effects
				(font
					(size 1.27 1.27)
					(thickness 0.15)
				)
				(justify left bottom)
				(hide yes)
			)
		)
		(property "Datasheet" "https://www.bourns.com/docs/product-datasheets/cr.pdf"
			(at 153.67 48.26 0)
			(effects
				(font
					(size 1.27 1.27)
					(thickness 0.15)
				)
				(justify left bottom)
				(hide yes)
			)
		)
		(property "Description" "SMD Chip Resistor, 470 ohm, ± 1%, 62.5 mW, 0402 [1005 Metric], Thick Film, General Purpose"
			(at 135.89 68.58 0)
			(effects
				(font
					(size 1.27 1.27)
				)
				(hide yes)
			)
		)
		(property "Manufacturer" "Bourns"
			(at 158.75 48.26 0)
			(effects
				(font
					(size 1.27 1.27)
					(thickness 0.15)
				)
				(justify left bottom)
				(hide yes)
			)
		)
		(property "MPN" "CR0402-FX-4700GLF"
			(at 156.21 48.26 0)
			(effects
				(font
					(size 1.27 1.27)
					(thickness 0.15)
				)
				(justify left bottom)
				(hide yes)
			)
		)
		(property "Val" "470R"
			(at 133.35 67.3099 90)
			(effects
				(font
					(size 1.27 1.27)
					(thickness 0.15)
				)
				(justify left)
			)
		)
		(property "License" "Apache-2.0"
			(at 161.29 48.26 0)
			(effects
				(font
					(size 1.27 1.27)
					(thickness 0.15)
				)
				(justify left bottom)
				(hide yes)
			)
		)
		(property "Author" "Antmicro"
			(at 163.83 48.26 0)
			(effects
				(font
					(size 1.27 1.27)
					(thickness 0.15)
				)
				(justify left bottom)
				(hide yes)
			)
		)
		(property "Tolerance" "1%"
			(at 146.05 48.26 0)
			(effects
				(font
					(size 1.27 1.27)
				)
				(justify left bottom)
				(hide yes)
			)
		)
		(property "Public" "False"
			(at 166.37 48.26 0)
			(effects
				(font
					(size 1.27 1.27)
				)
				(justify left bottom)
				(hide yes)
			)
		)
		(pin "1"
		)
		(pin "2"
		)
		(instances
			(project "environment-sensor"
				(path ""
					(reference "R12")
					(unit 1)
				)
			)
		)
	)
	(symbol
		(lib_id "antmicropower:GND")
		(at 219.71 119.38 0)
		(mirror y)
		(unit 1)
		(exclude_from_sim no)
		(in_bom yes)
		(on_board yes)
		(dnp no)
		(fields_autoplaced yes)
		(property "Reference" "#PWR046"
			(at 219.71 125.73 0)
			(effects
				(font
					(size 1.27 1.27)
				)
				(hide yes)
			)
		)
		(property "Value" "GND"
			(at 219.71 124.46 0)
			(effects
				(font
					(size 1.27 1.27)
				)
			)
		)
		(property "Footprint" ""
			(at 219.71 119.38 0)
			(effects
				(font
					(size 1.27 1.27)
				)
				(hide yes)
			)
		)
		(property "Datasheet" ""
			(at 219.71 119.38 0)
			(effects
				(font
					(size 1.27 1.27)
				)
				(hide yes)
			)
		)
		(property "Description" ""
			(at 219.71 119.38 0)
			(effects
				(font
					(size 1.27 1.27)
				)
				(hide yes)
			)
		)
		(property "Author" "Antmicro"
			(at 210.82 127 0)
			(effects
				(font
					(size 1.27 1.27)
					(thickness 0.15)
				)
				(justify left bottom)
				(hide yes)
			)
		)
		(property "License" "Apache-2.0"
			(at 210.82 129.54 0)
			(effects
				(font
					(size 1.27 1.27)
					(thickness 0.15)
				)
				(justify left bottom)
				(hide yes)
			)
		)
		(pin "1"
		)
		(instances
			(project "environment-sensor"
				(path ""
					(reference "#PWR046")
					(unit 1)
				)
			)
		)
	)
	(symbol
		(lib_id "antmicroCapacitors0402:C_100n_0402")
		(at 387.35 160.02 90)
		(unit 1)
		(exclude_from_sim no)
		(in_bom yes)
		(on_board yes)
		(dnp no)
		(fields_autoplaced yes)
		(property "Reference" "C27"
			(at 389.89 156.2035 90)
			(effects
				(font
					(size 1.27 1.27)
					(thickness 0.15)
				)
				(justify right)
			)
		)
		(property "Value" "C_100n_0402"
			(at 397.51 139.7 0)
			(effects
				(font
					(size 1.27 1.27)
					(thickness 0.15)
				)
				(justify left bottom)
				(hide yes)
			)
		)
		(property "Footprint" "antmicro-footprints:C_0402_1005Metric"
			(at 400.05 139.7 0)
			(effects
				(font
					(size 1.27 1.27)
					(thickness 0.15)
				)
				(justify left bottom)
				(hide yes)
			)
		)
		(property "Datasheet" "https://www.murata.com/products/productdetail?partno=GRM155R61H104KE14%23"
			(at 402.59 139.7 0)
			(effects
				(font
					(size 1.27 1.27)
					(thickness 0.15)
				)
				(justify left bottom)
				(hide yes)
			)
		)
		(property "Description" "SMD Multilayer Ceramic Capacitor, 0.1 µF, 50 V, 0402 [1005 Metric], ± 10%, X5R, GRM Series"
			(at 387.35 160.02 0)
			(effects
				(font
					(size 1.27 1.27)
				)
				(hide yes)
			)
		)
		(property "Manufacturer" "Murata"
			(at 407.67 139.7 0)
			(effects
				(font
					(size 1.27 1.27)
					(thickness 0.15)
				)
				(justify left bottom)
				(hide yes)
			)
		)
		(property "MPN" "GRM155R61H104KE14D"
			(at 405.13 139.7 0)
			(effects
				(font
					(size 1.27 1.27)
					(thickness 0.15)
				)
				(justify left bottom)
				(hide yes)
			)
		)
		(property "Val" "100n"
			(at 389.89 158.7435 90)
			(effects
				(font
					(size 1.27 1.27)
					(thickness 0.15)
				)
				(justify right)
			)
		)
		(property "License" "Apache-2.0"
			(at 410.21 139.7 0)
			(effects
				(font
					(size 1.27 1.27)
					(thickness 0.15)
				)
				(justify left bottom)
				(hide yes)
			)
		)
		(property "Author" "Antmicro"
			(at 412.75 139.7 0)
			(effects
				(font
					(size 1.27 1.27)
					(thickness 0.15)
				)
				(justify left bottom)
				(hide yes)
			)
		)
		(property "Voltage" "50V"
			(at 415.29 139.7 0)
			(effects
				(font
					(size 1.27 1.27)
				)
				(justify left bottom)
				(hide yes)
			)
		)
		(property "Dielectric" "X5R"
			(at 417.83 139.7 0)
			(effects
				(font
					(size 1.27 1.27)
				)
				(justify left bottom)
				(hide yes)
			)
		)
		(property "Public" "False"
			(at 420.37 139.7 0)
			(effects
				(font
					(size 1.27 1.27)
				)
				(justify left bottom)
				(hide yes)
			)
		)
		(pin "1"
		)
		(pin "2"
		)
		(instances
			(project "environment-sensor"
				(path ""
					(reference "C27")
					(unit 1)
				)
			)
		)
	)
	(symbol
		(lib_id "antmicroHumidityMoistureSensors:SHT45")
		(at 355.6 119.38 0)
		(unit 1)
		(exclude_from_sim no)
		(in_bom yes)
		(on_board yes)
		(dnp no)
		(fields_autoplaced yes)
		(property "Reference" "U5"
			(at 369.57 123.1899 0)
			(effects
				(font
					(size 1.27 1.27)
				)
				(justify left)
			)
		)
		(property "Value" "SHT45"
			(at 369.57 125.7299 0)
			(effects
				(font
					(size 1.27 1.27)
				)
				(justify left)
			)
		)
		(property "Footprint" "antmicro-footprints:Sensirion_DFN-4-1.5x1.5x0.5mm_P0.8mm"
			(at 363.22 115.57 0)
			(effects
				(font
					(size 1.27 1.27)
				)
				(justify left)
				(hide yes)
			)
		)
		(property "Datasheet" "https://sensirion.com/products/catalog/SHT45/"
			(at 363.22 118.11 0)
			(effects
				(font
					(size 1.27 1.27)
				)
				(justify left)
				(hide yes)
			)
		)
		(property "Description" "Sensor"
			(at 355.6 119.38 0)
			(effects
				(font
					(size 1.27 1.27)
				)
				(hide yes)
			)
		)
		(property "Manufacturer" "Sensirion"
			(at 369.57 128.2699 0)
			(effects
				(font
					(size 1.27 1.27)
				)
				(justify left)
			)
		)
		(property "MPN" "SHT45-AD1B-R2"
			(at 369.57 130.8099 0)
			(effects
				(font
					(size 1.27 1.27)
				)
				(justify left)
			)
		)
		(property "Author" "Antmicro"
			(at 383.54 139.7 0)
			(effects
				(font
					(size 1.27 1.27)
					(thickness 0.15)
				)
				(justify left bottom)
				(hide yes)
			)
		)
		(property "License" "Apache-2.0"
			(at 383.54 142.24 0)
			(effects
				(font
					(size 1.27 1.27)
					(thickness 0.15)
				)
				(justify left bottom)
				(hide yes)
			)
		)
		(pin "1"
		)
		(pin "2"
		)
		(pin "3"
		)
		(pin "4"
		)
		(instances
			(project "environment-sensor"
				(path ""
					(reference "U5")
					(unit 1)
				)
			)
		)
	)
	(symbol
		(lib_id "antmicroCapacitors0402:C_2u2_0402")
		(at 87.63 64.77 90)
		(unit 1)
		(exclude_from_sim no)
		(in_bom yes)
		(on_board yes)
		(dnp no)
		(fields_autoplaced yes)
		(property "Reference" "C4"
			(at 90.17 60.9535 90)
			(effects
				(font
					(size 1.27 1.27)
					(thickness 0.15)
				)
				(justify right)
			)
		)
		(property "Value" "C_2u2_0402"
			(at 97.79 44.45 0)
			(effects
				(font
					(size 1.27 1.27)
					(thickness 0.15)
				)
				(justify left bottom)
				(hide yes)
			)
		)
		(property "Footprint" "antmicro-footprints:C_0402_1005Metric"
			(at 100.33 44.45 0)
			(effects
				(font
					(size 1.27 1.27)
					(thickness 0.15)
				)
				(justify left bottom)
				(hide yes)
			)
		)
		(property "Datasheet" "https://product.tdk.com/en/search/capacitor/ceramic/mlcc/info?part_no=C1005X5R1A225K050BC"
			(at 102.87 44.45 0)
			(effects
				(font
					(size 1.27 1.27)
					(thickness 0.15)
				)
				(justify left bottom)
				(hide yes)
			)
		)
		(property "Description" "SMD Multilayer Ceramic Capacitor, 2.2 µF, 10 V, 0402 [1005 Metric], ± 10%, X5R, C"
			(at 87.63 64.77 0)
			(effects
				(font
					(size 1.27 1.27)
				)
				(hide yes)
			)
		)
		(property "Manufacturer" "TDK"
			(at 107.95 44.45 0)
			(effects
				(font
					(size 1.27 1.27)
					(thickness 0.15)
				)
				(justify left bottom)
				(hide yes)
			)
		)
		(property "MPN" "C1005X5R1A225K050BC"
			(at 105.41 44.45 0)
			(effects
				(font
					(size 1.27 1.27)
					(thickness 0.15)
				)
				(justify left bottom)
				(hide yes)
			)
		)
		(property "Val" "2u2"
			(at 90.17 63.4935 90)
			(effects
				(font
					(size 1.27 1.27)
					(thickness 0.15)
				)
				(justify right)
			)
		)
		(property "License" "Apache-2.0"
			(at 110.49 44.45 0)
			(effects
				(font
					(size 1.27 1.27)
					(thickness 0.15)
				)
				(justify left bottom)
				(hide yes)
			)
		)
		(property "Author" "Antmicro"
			(at 113.03 44.45 0)
			(effects
				(font
					(size 1.27 1.27)
					(thickness 0.15)
				)
				(justify left bottom)
				(hide yes)
			)
		)
		(property "Voltage" ""
			(at 115.57 44.45 0)
			(effects
				(font
					(size 1.27 1.27)
				)
				(justify left bottom)
				(hide yes)
			)
		)
		(property "Dielectric" ""
			(at 118.11 44.45 0)
			(effects
				(font
					(size 1.27 1.27)
				)
				(justify left bottom)
				(hide yes)
			)
		)
		(property "Public" "False"
			(at 120.65 44.45 0)
			(effects
				(font
					(size 1.27 1.27)
				)
				(justify left bottom)
				(hide yes)
			)
		)
		(pin "1"
		)
		(pin "2"
		)
		(instances
			(project "environment-sensor"
				(path ""
					(reference "C4")
					(unit 1)
				)
			)
		)
	)
	(symbol
		(lib_id "antmicropower:+3V3")
		(at 276.86 30.48 0)
		(mirror y)
		(unit 1)
		(exclude_from_sim no)
		(in_bom yes)
		(on_board yes)
		(dnp no)
		(fields_autoplaced yes)
		(property "Reference" "#PWR044"
			(at 276.86 34.29 0)
			(effects
				(font
					(size 1.27 1.27)
				)
				(hide yes)
			)
		)
		(property "Value" "+3V3"
			(at 276.86 25.4 0)
			(effects
				(font
					(size 1.27 1.27)
				)
			)
		)
		(property "Footprint" ""
			(at 276.86 30.48 0)
			(effects
				(font
					(size 1.27 1.27)
				)
				(hide yes)
			)
		)
		(property "Datasheet" ""
			(at 276.86 30.48 0)
			(effects
				(font
					(size 1.27 1.27)
				)
				(hide yes)
			)
		)
		(property "Description" ""
			(at 276.86 30.48 0)
			(effects
				(font
					(size 1.27 1.27)
				)
				(hide yes)
			)
		)
		(property "Author" "Antmicro"
			(at 261.62 33.02 0)
			(effects
				(font
					(size 1.27 1.27)
					(thickness 0.15)
				)
				(justify left bottom)
				(hide yes)
			)
		)
		(property "License" "Apache-2.0"
			(at 261.62 35.56 0)
			(effects
				(font
					(size 1.27 1.27)
					(thickness 0.15)
				)
				(justify left bottom)
				(hide yes)
			)
		)
		(pin "1"
		)
		(instances
			(project "environment-sensor"
				(path ""
					(reference "#PWR044")
					(unit 1)
				)
			)
		)
	)
	(symbol
		(lib_id "antmicropower:GND")
		(at 332.74 231.14 0)
		(mirror y)
		(unit 1)
		(exclude_from_sim no)
		(in_bom yes)
		(on_board yes)
		(dnp no)
		(fields_autoplaced yes)
		(property "Reference" "#PWR063"
			(at 332.74 237.49 0)
			(effects
				(font
					(size 1.27 1.27)
				)
				(hide yes)
			)
		)
		(property "Value" "GND"
			(at 332.74 236.22 0)
			(effects
				(font
					(size 1.27 1.27)
				)
			)
		)
		(property "Footprint" ""
			(at 332.74 231.14 0)
			(effects
				(font
					(size 1.27 1.27)
				)
				(hide yes)
			)
		)
		(property "Datasheet" ""
			(at 332.74 231.14 0)
			(effects
				(font
					(size 1.27 1.27)
				)
				(hide yes)
			)
		)
		(property "Description" ""
			(at 332.74 231.14 0)
			(effects
				(font
					(size 1.27 1.27)
				)
				(hide yes)
			)
		)
		(property "Author" "Antmicro"
			(at 323.85 238.76 0)
			(effects
				(font
					(size 1.27 1.27)
					(thickness 0.15)
				)
				(justify left bottom)
				(hide yes)
			)
		)
		(property "License" "Apache-2.0"
			(at 323.85 241.3 0)
			(effects
				(font
					(size 1.27 1.27)
					(thickness 0.15)
				)
				(justify left bottom)
				(hide yes)
			)
		)
		(pin "1"
		)
		(instances
			(project "environment-sensor"
				(path ""
					(reference "#PWR063")
					(unit 1)
				)
			)
		)
	)
	(symbol
		(lib_id "antmicropower:+3V3")
		(at 336.55 156.21 0)
		(mirror y)
		(unit 1)
		(exclude_from_sim no)
		(in_bom yes)
		(on_board yes)
		(dnp no)
		(fields_autoplaced yes)
		(property "Reference" "#PWR061"
			(at 336.55 160.02 0)
			(effects
				(font
					(size 1.27 1.27)
				)
				(hide yes)
			)
		)
		(property "Value" "+3V3"
			(at 336.55 151.13 0)
			(effects
				(font
					(size 1.27 1.27)
				)
			)
		)
		(property "Footprint" ""
			(at 336.55 156.21 0)
			(effects
				(font
					(size 1.27 1.27)
				)
				(hide yes)
			)
		)
		(property "Datasheet" ""
			(at 336.55 156.21 0)
			(effects
				(font
					(size 1.27 1.27)
				)
				(hide yes)
			)
		)
		(property "Description" ""
			(at 336.55 156.21 0)
			(effects
				(font
					(size 1.27 1.27)
				)
				(hide yes)
			)
		)
		(property "Author" "Antmicro"
			(at 321.31 158.75 0)
			(effects
				(font
					(size 1.27 1.27)
					(thickness 0.15)
				)
				(justify left bottom)
				(hide yes)
			)
		)
		(property "License" "Apache-2.0"
			(at 321.31 161.29 0)
			(effects
				(font
					(size 1.27 1.27)
					(thickness 0.15)
				)
				(justify left bottom)
				(hide yes)
			)
		)
		(pin "1"
		)
		(instances
			(project "environment-sensor"
				(path ""
					(reference "#PWR061")
					(unit 1)
				)
			)
		)
	)
	(symbol
		(lib_id "antmicropower:GND")
		(at 276.86 118.11 0)
		(mirror y)
		(unit 1)
		(exclude_from_sim no)
		(in_bom yes)
		(on_board yes)
		(dnp no)
		(fields_autoplaced yes)
		(property "Reference" "#PWR029"
			(at 276.86 124.46 0)
			(effects
				(font
					(size 1.27 1.27)
				)
				(hide yes)
			)
		)
		(property "Value" "GND"
			(at 276.86 123.19 0)
			(effects
				(font
					(size 1.27 1.27)
				)
			)
		)
		(property "Footprint" ""
			(at 276.86 118.11 0)
			(effects
				(font
					(size 1.27 1.27)
				)
				(hide yes)
			)
		)
		(property "Datasheet" ""
			(at 276.86 118.11 0)
			(effects
				(font
					(size 1.27 1.27)
				)
				(hide yes)
			)
		)
		(property "Description" ""
			(at 276.86 118.11 0)
			(effects
				(font
					(size 1.27 1.27)
				)
				(hide yes)
			)
		)
		(property "Author" "Antmicro"
			(at 267.97 125.73 0)
			(effects
				(font
					(size 1.27 1.27)
					(thickness 0.15)
				)
				(justify left bottom)
				(hide yes)
			)
		)
		(property "License" "Apache-2.0"
			(at 267.97 128.27 0)
			(effects
				(font
					(size 1.27 1.27)
					(thickness 0.15)
				)
				(justify left bottom)
				(hide yes)
			)
		)
		(pin "1"
		)
		(instances
			(project "environment-sensor"
				(path ""
					(reference "#PWR029")
					(unit 1)
				)
			)
		)
	)
	(symbol
		(lib_id "antmicroResistors0402:R_5k1_0402")
		(at 388.62 45.72 90)
		(unit 1)
		(exclude_from_sim no)
		(in_bom yes)
		(on_board yes)
		(dnp no)
		(fields_autoplaced yes)
		(property "Reference" "R38"
			(at 391.16 41.9099 90)
			(effects
				(font
					(size 1.27 1.27)
					(thickness 0.15)
				)
				(justify right)
			)
		)
		(property "Value" "R_5k1_0402"
			(at 401.32 25.4 0)
			(effects
				(font
					(size 1.27 1.27)
					(thickness 0.15)
				)
				(justify left bottom)
				(hide yes)
			)
		)
		(property "Footprint" "antmicro-footprints:R_0402_1005Metric"
			(at 403.86 25.4 0)
			(effects
				(font
					(size 1.27 1.27)
					(thickness 0.15)
				)
				(justify left bottom)
				(hide yes)
			)
		)
		(property "Datasheet" "https://www.bourns.com/docs/product-datasheets/cr.pdf"
			(at 406.4 25.4 0)
			(effects
				(font
					(size 1.27 1.27)
					(thickness 0.15)
				)
				(justify left bottom)
				(hide yes)
			)
		)
		(property "Description" "SMD Chip Resistor, 5.1 kohm, ± 1%, 63 mW, 0402 [1005 Metric], Thick Film, General Purpose"
			(at 388.62 45.72 0)
			(effects
				(font
					(size 1.27 1.27)
				)
				(hide yes)
			)
		)
		(property "Manufacturer" "Bourns"
			(at 411.48 25.4 0)
			(effects
				(font
					(size 1.27 1.27)
					(thickness 0.15)
				)
				(justify left bottom)
				(hide yes)
			)
		)
		(property "MPN" "CR0402-FX-5101GLF"
			(at 408.94 25.4 0)
			(effects
				(font
					(size 1.27 1.27)
					(thickness 0.15)
				)
				(justify left bottom)
				(hide yes)
			)
		)
		(property "Val" "5k1"
			(at 391.16 44.4499 90)
			(effects
				(font
					(size 1.27 1.27)
					(thickness 0.15)
				)
				(justify right)
			)
		)
		(property "License" "Apache-2.0"
			(at 414.02 25.4 0)
			(effects
				(font
					(size 1.27 1.27)
					(thickness 0.15)
				)
				(justify left bottom)
				(hide yes)
			)
		)
		(property "Author" "Antmicro"
			(at 416.56 25.4 0)
			(effects
				(font
					(size 1.27 1.27)
					(thickness 0.15)
				)
				(justify left bottom)
				(hide yes)
			)
		)
		(property "Tolerance" "1%"
			(at 398.78 25.4 0)
			(effects
				(font
					(size 1.27 1.27)
				)
				(justify left bottom)
				(hide yes)
			)
		)
		(property "Public" "False"
			(at 419.1 25.4 0)
			(effects
				(font
					(size 1.27 1.27)
				)
				(justify left bottom)
				(hide yes)
			)
		)
		(pin "1"
		)
		(pin "2"
		)
		(instances
			(project "environment-sensor"
				(path ""
					(reference "R38")
					(unit 1)
				)
			)
		)
	)
	(symbol
		(lib_id "antmicropower:GNDREF")
		(at 224.79 34.29 0)
		(unit 1)
		(exclude_from_sim no)
		(in_bom yes)
		(on_board yes)
		(dnp no)
		(fields_autoplaced yes)
		(property "Reference" "#PWR033"
			(at 224.79 40.64 0)
			(effects
				(font
					(size 1.27 1.27)
				)
				(hide yes)
			)
		)
		(property "Value" "GNDREF"
			(at 224.79 38.735 0)
			(effects
				(font
					(size 1.27 1.27)
				)
			)
		)
		(property "Footprint" ""
			(at 224.79 34.29 0)
			(effects
				(font
					(size 1.27 1.27)
				)
				(hide yes)
			)
		)
		(property "Datasheet" ""
			(at 224.79 34.29 0)
			(effects
				(font
					(size 1.27 1.27)
				)
				(hide yes)
			)
		)
		(property "Description" ""
			(at 224.79 34.29 0)
			(effects
				(font
					(size 1.27 1.27)
				)
				(hide yes)
			)
		)
		(pin "1"
		)
		(instances
			(project "environment-sensor"
				(path ""
					(reference "#PWR033")
					(unit 1)
				)
			)
		)
	)
	(symbol
		(lib_id "antmicroCapacitors0402:C_2u2_0402")
		(at 193.04 118.11 270)
		(mirror x)
		(unit 1)
		(exclude_from_sim no)
		(in_bom yes)
		(on_board yes)
		(dnp no)
		(fields_autoplaced yes)
		(property "Reference" "C24"
			(at 190.5 114.2935 90)
			(effects
				(font
					(size 1.27 1.27)
					(thickness 0.15)
				)
				(justify right)
			)
		)
		(property "Value" "C_2u2_0402"
			(at 182.88 97.79 0)
			(effects
				(font
					(size 1.27 1.27)
					(thickness 0.15)
				)
				(justify left bottom)
				(hide yes)
			)
		)
		(property "Footprint" "antmicro-footprints:C_0402_1005Metric"
			(at 180.34 97.79 0)
			(effects
				(font
					(size 1.27 1.27)
					(thickness 0.15)
				)
				(justify left bottom)
				(hide yes)
			)
		)
		(property "Datasheet" "https://product.tdk.com/en/search/capacitor/ceramic/mlcc/info?part_no=C1005X5R1A225K050BC"
			(at 177.8 97.79 0)
			(effects
				(font
					(size 1.27 1.27)
					(thickness 0.15)
				)
				(justify left bottom)
				(hide yes)
			)
		)
		(property "Description" "SMD Multilayer Ceramic Capacitor, 2.2 µF, 10 V, 0402 [1005 Metric], ± 10%, X5R, C"
			(at 193.04 118.11 0)
			(effects
				(font
					(size 1.27 1.27)
				)
				(hide yes)
			)
		)
		(property "Manufacturer" "TDK"
			(at 172.72 97.79 0)
			(effects
				(font
					(size 1.27 1.27)
					(thickness 0.15)
				)
				(justify left bottom)
				(hide yes)
			)
		)
		(property "MPN" "C1005X5R1A225K050BC"
			(at 175.26 97.79 0)
			(effects
				(font
					(size 1.27 1.27)
					(thickness 0.15)
				)
				(justify left bottom)
				(hide yes)
			)
		)
		(property "Val" "2u2"
			(at 190.5 116.8335 90)
			(effects
				(font
					(size 1.27 1.27)
					(thickness 0.15)
				)
				(justify right)
			)
		)
		(property "License" "Apache-2.0"
			(at 170.18 97.79 0)
			(effects
				(font
					(size 1.27 1.27)
					(thickness 0.15)
				)
				(justify left bottom)
				(hide yes)
			)
		)
		(property "Author" "Antmicro"
			(at 167.64 97.79 0)
			(effects
				(font
					(size 1.27 1.27)
					(thickness 0.15)
				)
				(justify left bottom)
				(hide yes)
			)
		)
		(property "Voltage" ""
			(at 165.1 97.79 0)
			(effects
				(font
					(size 1.27 1.27)
				)
				(justify left bottom)
				(hide yes)
			)
		)
		(property "Dielectric" ""
			(at 162.56 97.79 0)
			(effects
				(font
					(size 1.27 1.27)
				)
				(justify left bottom)
				(hide yes)
			)
		)
		(property "Public" "False"
			(at 160.02 97.79 0)
			(effects
				(font
					(size 1.27 1.27)
				)
				(justify left bottom)
				(hide yes)
			)
		)
		(pin "1"
		)
		(pin "2"
		)
		(instances
			(project "environment-sensor"
				(path ""
					(reference "C24")
					(unit 1)
				)
			)
		)
	)
	(symbol
		(lib_id "antmicroCapacitors0402:C_100n_0402")
		(at 382.27 116.84 270)
		(unit 1)
		(exclude_from_sim no)
		(in_bom yes)
		(on_board yes)
		(dnp no)
		(fields_autoplaced yes)
		(property "Reference" "C26"
			(at 384.81 118.1162 90)
			(effects
				(font
					(size 1.27 1.27)
					(thickness 0.15)
				)
				(justify left)
			)
		)
		(property "Value" "C_100n_0402"
			(at 372.11 137.16 0)
			(effects
				(font
					(size 1.27 1.27)
					(thickness 0.15)
				)
				(justify left bottom)
				(hide yes)
			)
		)
		(property "Footprint" "antmicro-footprints:C_0402_1005Metric"
			(at 369.57 137.16 0)
			(effects
				(font
					(size 1.27 1.27)
					(thickness 0.15)
				)
				(justify left bottom)
				(hide yes)
			)
		)
		(property "Datasheet" "https://www.murata.com/products/productdetail?partno=GRM155R61H104KE14%23"
			(at 367.03 137.16 0)
			(effects
				(font
					(size 1.27 1.27)
					(thickness 0.15)
				)
				(justify left bottom)
				(hide yes)
			)
		)
		(property "Description" "SMD Multilayer Ceramic Capacitor, 0.1 µF, 50 V, 0402 [1005 Metric], ± 10%, X5R, GRM Series"
			(at 382.27 116.84 0)
			(effects
				(font
					(size 1.27 1.27)
				)
				(hide yes)
			)
		)
		(property "Manufacturer" "Murata"
			(at 361.95 137.16 0)
			(effects
				(font
					(size 1.27 1.27)
					(thickness 0.15)
				)
				(justify left bottom)
				(hide yes)
			)
		)
		(property "MPN" "GRM155R61H104KE14D"
			(at 364.49 137.16 0)
			(effects
				(font
					(size 1.27 1.27)
					(thickness 0.15)
				)
				(justify left bottom)
				(hide yes)
			)
		)
		(property "Val" "100n"
			(at 384.81 120.6562 90)
			(effects
				(font
					(size 1.27 1.27)
					(thickness 0.15)
				)
				(justify left)
			)
		)
		(property "License" "Apache-2.0"
			(at 359.41 137.16 0)
			(effects
				(font
					(size 1.27 1.27)
					(thickness 0.15)
				)
				(justify left bottom)
				(hide yes)
			)
		)
		(property "Author" "Antmicro"
			(at 356.87 137.16 0)
			(effects
				(font
					(size 1.27 1.27)
					(thickness 0.15)
				)
				(justify left bottom)
				(hide yes)
			)
		)
		(property "Voltage" "50V"
			(at 354.33 137.16 0)
			(effects
				(font
					(size 1.27 1.27)
				)
				(justify left bottom)
				(hide yes)
			)
		)
		(property "Dielectric" "X5R"
			(at 351.79 137.16 0)
			(effects
				(font
					(size 1.27 1.27)
				)
				(justify left bottom)
				(hide yes)
			)
		)
		(property "Public" "False"
			(at 349.25 137.16 0)
			(effects
				(font
					(size 1.27 1.27)
				)
				(justify left bottom)
				(hide yes)
			)
		)
		(pin "1"
		)
		(pin "2"
		)
		(instances
			(project "environment-sensor"
				(path ""
					(reference "C26")
					(unit 1)
				)
			)
		)
	)
	(symbol
		(lib_id "antmicropower:GND")
		(at 398.78 161.29 0)
		(mirror y)
		(unit 1)
		(exclude_from_sim no)
		(in_bom yes)
		(on_board yes)
		(dnp no)
		(fields_autoplaced yes)
		(property "Reference" "#PWR078"
			(at 398.78 167.64 0)
			(effects
				(font
					(size 1.27 1.27)
				)
				(hide yes)
			)
		)
		(property "Value" "GND"
			(at 398.78 166.37 0)
			(effects
				(font
					(size 1.27 1.27)
				)
			)
		)
		(property "Footprint" ""
			(at 398.78 161.29 0)
			(effects
				(font
					(size 1.27 1.27)
				)
				(hide yes)
			)
		)
		(property "Datasheet" ""
			(at 398.78 161.29 0)
			(effects
				(font
					(size 1.27 1.27)
				)
				(hide yes)
			)
		)
		(property "Description" ""
			(at 398.78 161.29 0)
			(effects
				(font
					(size 1.27 1.27)
				)
				(hide yes)
			)
		)
		(property "Author" "Antmicro"
			(at 389.89 168.91 0)
			(effects
				(font
					(size 1.27 1.27)
					(thickness 0.15)
				)
				(justify left bottom)
				(hide yes)
			)
		)
		(property "License" "Apache-2.0"
			(at 389.89 171.45 0)
			(effects
				(font
					(size 1.27 1.27)
					(thickness 0.15)
				)
				(justify left bottom)
				(hide yes)
			)
		)
		(pin "1"
		)
		(instances
			(project "environment-sensor"
				(path ""
					(reference "#PWR078")
					(unit 1)
				)
			)
		)
	)
	(symbol
		(lib_id "antmicropower:GND")
		(at 118.11 171.45 0)
		(unit 1)
		(exclude_from_sim no)
		(in_bom yes)
		(on_board yes)
		(dnp no)
		(fields_autoplaced yes)
		(property "Reference" "#PWR017"
			(at 118.11 177.8 0)
			(effects
				(font
					(size 1.27 1.27)
				)
				(hide yes)
			)
		)
		(property "Value" "GND"
			(at 121.285 173.99 0)
			(effects
				(font
					(size 1.27 1.27)
				)
			)
		)
		(property "Footprint" ""
			(at 118.11 171.45 0)
			(effects
				(font
					(size 1.27 1.27)
				)
				(hide yes)
			)
		)
		(property "Datasheet" ""
			(at 118.11 171.45 0)
			(effects
				(font
					(size 1.27 1.27)
				)
				(hide yes)
			)
		)
		(property "Description" ""
			(at 118.11 171.45 0)
			(effects
				(font
					(size 1.27 1.27)
				)
				(hide yes)
			)
		)
		(property "Author" "Antmicro"
			(at 127 179.07 0)
			(effects
				(font
					(size 1.27 1.27)
					(thickness 0.15)
				)
				(justify left bottom)
				(hide yes)
			)
		)
		(property "License" "Apache-2.0"
			(at 127 181.61 0)
			(effects
				(font
					(size 1.27 1.27)
					(thickness 0.15)
				)
				(justify left bottom)
				(hide yes)
			)
		)
		(pin "1"
		)
		(instances
			(project "environment-sensor"
				(path ""
					(reference "#PWR017")
					(unit 1)
				)
			)
		)
	)
	(symbol
		(lib_id "antmicroCapacitors0402:C_16p_0402")
		(at 218.44 210.82 270)
		(unit 1)
		(exclude_from_sim no)
		(in_bom yes)
		(on_board yes)
		(dnp no)
		(fields_autoplaced yes)
		(property "Reference" "C16"
			(at 220.98 212.0962 90)
			(effects
				(font
					(size 1.27 1.27)
					(thickness 0.15)
				)
				(justify left)
			)
		)
		(property "Value" "C_16p_0402"
			(at 208.28 231.14 0)
			(effects
				(font
					(size 1.27 1.27)
					(thickness 0.15)
				)
				(justify left bottom)
				(hide yes)
			)
		)
		(property "Footprint" "antmicro-footprints:C_0402_1005Metric"
			(at 205.74 231.14 0)
			(effects
				(font
					(size 1.27 1.27)
					(thickness 0.15)
				)
				(justify left bottom)
				(hide yes)
			)
		)
		(property "Datasheet" "https://www.passivecomponent.com/wp-content/uploads/datasheet/WTC_MLCC_General_Purpose.pdf"
			(at 203.2 231.14 0)
			(effects
				(font
					(size 1.27 1.27)
					(thickness 0.15)
				)
				(justify left bottom)
				(hide yes)
			)
		)
		(property "Description" "SMD Multilayer Ceramic Capacitor, General Purpose, 16 pF, 50 V, 0402 [1005 Metric], ± 5%, C0G / NP0"
			(at 218.44 210.82 0)
			(effects
				(font
					(size 1.27 1.27)
				)
				(hide yes)
			)
		)
		(property "Manufacturer" "Walsin"
			(at 198.12 231.14 0)
			(effects
				(font
					(size 1.27 1.27)
					(thickness 0.15)
				)
				(justify left bottom)
				(hide yes)
			)
		)
		(property "MPN" "0402N160J500CT"
			(at 200.66 231.14 0)
			(effects
				(font
					(size 1.27 1.27)
					(thickness 0.15)
				)
				(justify left bottom)
				(hide yes)
			)
		)
		(property "Val" "16p"
			(at 220.98 214.6362 90)
			(effects
				(font
					(size 1.27 1.27)
					(thickness 0.15)
				)
				(justify left)
			)
		)
		(property "License" "Apache-2.0"
			(at 195.58 231.14 0)
			(effects
				(font
					(size 1.27 1.27)
					(thickness 0.15)
				)
				(justify left bottom)
				(hide yes)
			)
		)
		(property "Author" "Antmicro"
			(at 193.04 231.14 0)
			(effects
				(font
					(size 1.27 1.27)
					(thickness 0.15)
				)
				(justify left bottom)
				(hide yes)
			)
		)
		(property "Voltage" ""
			(at 190.5 231.14 0)
			(effects
				(font
					(size 1.27 1.27)
				)
				(justify left bottom)
				(hide yes)
			)
		)
		(property "Dielectric" ""
			(at 187.96 231.14 0)
			(effects
				(font
					(size 1.27 1.27)
				)
				(justify left bottom)
				(hide yes)
			)
		)
		(property "Public" "False"
			(at 185.42 231.14 0)
			(effects
				(font
					(size 1.27 1.27)
				)
				(justify left bottom)
				(hide yes)
			)
		)
		(pin "1"
		)
		(pin "2"
		)
		(instances
			(project "environment-sensor"
				(path ""
					(reference "C16")
					(unit 1)
				)
			)
		)
	)
	(symbol
		(lib_id "antmicropower:+3V3")
		(at 200.66 137.16 0)
		(unit 1)
		(exclude_from_sim no)
		(in_bom yes)
		(on_board yes)
		(dnp no)
		(fields_autoplaced yes)
		(property "Reference" "#PWR034"
			(at 200.66 140.97 0)
			(effects
				(font
					(size 1.27 1.27)
				)
				(hide yes)
			)
		)
		(property "Value" "+3V3"
			(at 196.85 135.89 0)
			(effects
				(font
					(size 1.27 1.27)
				)
			)
		)
		(property "Footprint" ""
			(at 200.66 137.16 0)
			(effects
				(font
					(size 1.27 1.27)
				)
				(hide yes)
			)
		)
		(property "Datasheet" ""
			(at 200.66 137.16 0)
			(effects
				(font
					(size 1.27 1.27)
				)
				(hide yes)
			)
		)
		(property "Description" ""
			(at 200.66 137.16 0)
			(effects
				(font
					(size 1.27 1.27)
				)
				(hide yes)
			)
		)
		(property "Author" "Antmicro"
			(at 215.9 139.7 0)
			(effects
				(font
					(size 1.27 1.27)
					(thickness 0.15)
				)
				(justify left bottom)
				(hide yes)
			)
		)
		(property "License" "Apache-2.0"
			(at 215.9 142.24 0)
			(effects
				(font
					(size 1.27 1.27)
					(thickness 0.15)
				)
				(justify left bottom)
				(hide yes)
			)
		)
		(pin "1"
		)
		(instances
			(project "environment-sensor"
				(path ""
					(reference "#PWR034")
					(unit 1)
				)
			)
		)
	)
	(symbol
		(lib_id "antmicroTVSDiodes:ESD9X5.0ST5G")
		(at 59.69 73.66 90)
		(unit 1)
		(exclude_from_sim no)
		(in_bom yes)
		(on_board yes)
		(dnp no)
		(fields_autoplaced yes)
		(property "Reference" "D1"
			(at 63.5 68.2624 90)
			(effects
				(font
					(size 1.27 1.27)
					(thickness 0.15)
				)
				(justify right)
			)
		)
		(property "Value" "ESD9X5.0ST5G"
			(at 63.5 70.8024 90)
			(effects
				(font
					(size 1.27 1.27)
					(thickness 0.15)
				)
				(justify right)
			)
		)
		(property "Footprint" "antmicro-footprints:SOD-923"
			(at 67.31 52.07 0)
			(effects
				(font
					(size 1.27 1.27)
					(thickness 0.15)
				)
				(justify left bottom)
				(hide yes)
			)
		)
		(property "Datasheet" "https://www.onsemi.com/pdf/datasheet/esd9x3.3st5g-d.pdf"
			(at 69.85 52.07 0)
			(effects
				(font
					(size 1.27 1.27)
					(thickness 0.15)
				)
				(justify left bottom)
				(hide yes)
			)
		)
		(property "Description" "Unidirectional TVS, 30 kV,  SOD-923, 5 V, 65 pF"
			(at 59.69 73.66 0)
			(effects
				(font
					(size 1.27 1.27)
				)
				(hide yes)
			)
		)
		(property "Manufacturer" "ON Semiconductor"
			(at 72.39 52.07 0)
			(effects
				(font
					(size 1.27 1.27)
					(thickness 0.15)
				)
				(justify left bottom)
				(hide yes)
			)
		)
		(property "MPN" "ESD9X5.0ST5G"
			(at 74.93 52.07 0)
			(effects
				(font
					(size 1.27 1.27)
					(thickness 0.15)
				)
				(justify left bottom)
				(hide yes)
			)
		)
		(property "Author" "Antmicro"
			(at 77.47 52.07 0)
			(effects
				(font
					(size 1.27 1.27)
					(thickness 0.15)
				)
				(justify left bottom)
				(hide yes)
			)
		)
		(property "License" "Apache-2.0"
			(at 80.01 52.07 0)
			(effects
				(font
					(size 1.27 1.27)
					(thickness 0.15)
				)
				(justify left bottom)
				(hide yes)
			)
		)
		(property "Public" "False"
			(at 77.47 53.34 0)
			(effects
				(font
					(size 1.27 1.27)
				)
				(justify left bottom)
				(hide yes)
			)
		)
		(pin "1"
		)
		(pin "2"
		)
		(instances
			(project "environment-sensor"
				(path ""
					(reference "D1")
					(unit 1)
				)
			)
		)
	)
	(symbol
		(lib_id "antmicroResistors0402:R_100R_0402")
		(at 237.49 166.37 0)
		(mirror y)
		(unit 1)
		(exclude_from_sim no)
		(in_bom no)
		(on_board yes)
		(dnp yes)
		(fields_autoplaced yes)
		(property "Reference" "R21"
			(at 232.41 163.83 0)
			(effects
				(font
					(size 1.27 1.27)
					(thickness 0.15)
				)
			)
		)
		(property "Value" "R_100R_0402"
			(at 217.17 179.07 0)
			(effects
				(font
					(size 1.27 1.27)
					(thickness 0.15)
				)
				(justify left bottom)
				(hide yes)
			)
		)
		(property "Footprint" "antmicro-footprints:R_0402_1005Metric"
			(at 217.17 181.61 0)
			(effects
				(font
					(size 1.27 1.27)
					(thickness 0.15)
				)
				(justify left bottom)
				(hide yes)
			)
		)
		(property "Datasheet" "https://www.bourns.com/docs/product-datasheets/cr.pdf"
			(at 217.17 184.15 0)
			(effects
				(font
					(size 1.27 1.27)
					(thickness 0.15)
				)
				(justify left bottom)
				(hide yes)
			)
		)
		(property "Description" "SMD Chip Resistor, 100 ohm, ± 1%, 62.5 mW, 0402 [1005 Metric], Thick Film, General Purpose"
			(at 237.49 166.37 0)
			(effects
				(font
					(size 1.27 1.27)
				)
				(hide yes)
			)
		)
		(property "Manufacturer" "Bourns"
			(at 217.17 189.23 0)
			(effects
				(font
					(size 1.27 1.27)
					(thickness 0.15)
				)
				(justify left bottom)
				(hide yes)
			)
		)
		(property "MPN" "CR0402-FX-1000GLF"
			(at 217.17 186.69 0)
			(effects
				(font
					(size 1.27 1.27)
					(thickness 0.15)
				)
				(justify left bottom)
				(hide yes)
			)
		)
		(property "Val" "100R"
			(at 237.49 163.83 0)
			(effects
				(font
					(size 1.27 1.27)
					(thickness 0.15)
				)
			)
		)
		(property "License" "Apache-2.0"
			(at 217.17 191.77 0)
			(effects
				(font
					(size 1.27 1.27)
					(thickness 0.15)
				)
				(justify left bottom)
				(hide yes)
			)
		)
		(property "Author" "Antmicro"
			(at 217.17 194.31 0)
			(effects
				(font
					(size 1.27 1.27)
					(thickness 0.15)
				)
				(justify left bottom)
				(hide yes)
			)
		)
		(property "Tolerance" "1%"
			(at 217.17 176.53 0)
			(effects
				(font
					(size 1.27 1.27)
				)
				(justify left bottom)
				(hide yes)
			)
		)
		(property "Public" "False"
			(at 217.17 196.85 0)
			(effects
				(font
					(size 1.27 1.27)
				)
				(justify left bottom)
				(hide yes)
			)
		)
		(pin "1"
		)
		(pin "2"
		)
		(instances
			(project "environment-sensor"
				(path ""
					(reference "R21")
					(unit 1)
				)
			)
		)
	)
	(symbol
		(lib_id "antmicropower:+3V3")
		(at 199.39 44.45 0)
		(unit 1)
		(exclude_from_sim no)
		(in_bom yes)
		(on_board yes)
		(dnp no)
		(fields_autoplaced yes)
		(property "Reference" "#PWR025"
			(at 199.39 48.26 0)
			(effects
				(font
					(size 1.27 1.27)
				)
				(hide yes)
			)
		)
		(property "Value" "+3V3"
			(at 199.39 39.37 0)
			(effects
				(font
					(size 1.27 1.27)
				)
			)
		)
		(property "Footprint" ""
			(at 199.39 44.45 0)
			(effects
				(font
					(size 1.27 1.27)
				)
				(hide yes)
			)
		)
		(property "Datasheet" ""
			(at 199.39 44.45 0)
			(effects
				(font
					(size 1.27 1.27)
				)
				(hide yes)
			)
		)
		(property "Description" ""
			(at 199.39 44.45 0)
			(effects
				(font
					(size 1.27 1.27)
				)
				(hide yes)
			)
		)
		(property "Author" "Antmicro"
			(at 214.63 46.99 0)
			(effects
				(font
					(size 1.27 1.27)
					(thickness 0.15)
				)
				(justify left bottom)
				(hide yes)
			)
		)
		(property "License" "Apache-2.0"
			(at 214.63 49.53 0)
			(effects
				(font
					(size 1.27 1.27)
					(thickness 0.15)
				)
				(justify left bottom)
				(hide yes)
			)
		)
		(pin "1"
		)
		(instances
			(project "environment-sensor"
				(path ""
					(reference "#PWR025")
					(unit 1)
				)
			)
		)
	)
	(symbol
		(lib_id "antmicroCapacitors0402:C_100n_0402")
		(at 118.11 170.18 90)
		(unit 1)
		(exclude_from_sim no)
		(in_bom yes)
		(on_board yes)
		(dnp no)
		(fields_autoplaced yes)
		(property "Reference" "C6"
			(at 120.65 166.3635 90)
			(effects
				(font
					(size 1.27 1.27)
					(thickness 0.15)
				)
				(justify right)
			)
		)
		(property "Value" "C_100n_0402"
			(at 128.27 149.86 0)
			(effects
				(font
					(size 1.27 1.27)
					(thickness 0.15)
				)
				(justify left bottom)
				(hide yes)
			)
		)
		(property "Footprint" "antmicro-footprints:C_0402_1005Metric"
			(at 130.81 149.86 0)
			(effects
				(font
					(size 1.27 1.27)
					(thickness 0.15)
				)
				(justify left bottom)
				(hide yes)
			)
		)
		(property "Datasheet" "https://www.murata.com/products/productdetail?partno=GRM155R61H104KE14%23"
			(at 133.35 149.86 0)
			(effects
				(font
					(size 1.27 1.27)
					(thickness 0.15)
				)
				(justify left bottom)
				(hide yes)
			)
		)
		(property "Description" "SMD Multilayer Ceramic Capacitor, 0.1 µF, 50 V, 0402 [1005 Metric], ± 10%, X5R, GRM Series"
			(at 118.11 170.18 0)
			(effects
				(font
					(size 1.27 1.27)
				)
				(hide yes)
			)
		)
		(property "Manufacturer" "Murata"
			(at 138.43 149.86 0)
			(effects
				(font
					(size 1.27 1.27)
					(thickness 0.15)
				)
				(justify left bottom)
				(hide yes)
			)
		)
		(property "MPN" "GRM155R61H104KE14D"
			(at 135.89 149.86 0)
			(effects
				(font
					(size 1.27 1.27)
					(thickness 0.15)
				)
				(justify left bottom)
				(hide yes)
			)
		)
		(property "Val" "100n"
			(at 120.65 168.9035 90)
			(effects
				(font
					(size 1.27 1.27)
					(thickness 0.15)
				)
				(justify right)
			)
		)
		(property "License" "Apache-2.0"
			(at 140.97 149.86 0)
			(effects
				(font
					(size 1.27 1.27)
					(thickness 0.15)
				)
				(justify left bottom)
				(hide yes)
			)
		)
		(property "Author" "Antmicro"
			(at 143.51 149.86 0)
			(effects
				(font
					(size 1.27 1.27)
					(thickness 0.15)
				)
				(justify left bottom)
				(hide yes)
			)
		)
		(property "Voltage" "50V"
			(at 146.05 149.86 0)
			(effects
				(font
					(size 1.27 1.27)
				)
				(justify left bottom)
				(hide yes)
			)
		)
		(property "Dielectric" "X5R"
			(at 148.59 149.86 0)
			(effects
				(font
					(size 1.27 1.27)
				)
				(justify left bottom)
				(hide yes)
			)
		)
		(property "Public" "False"
			(at 151.13 149.86 0)
			(effects
				(font
					(size 1.27 1.27)
				)
				(justify left bottom)
				(hide yes)
			)
		)
		(pin "1"
		)
		(pin "2"
		)
		(instances
			(project "environment-sensor"
				(path ""
					(reference "C6")
					(unit 1)
				)
			)
		)
	)
	(symbol
		(lib_id "antmicropower:GND")
		(at 36.83 187.96 0)
		(unit 1)
		(exclude_from_sim no)
		(in_bom yes)
		(on_board yes)
		(dnp no)
		(fields_autoplaced yes)
		(property "Reference" "#PWR03"
			(at 36.83 194.31 0)
			(effects
				(font
					(size 1.27 1.27)
				)
				(hide yes)
			)
		)
		(property "Value" "GND"
			(at 36.83 193.04 0)
			(effects
				(font
					(size 1.27 1.27)
				)
			)
		)
		(property "Footprint" ""
			(at 36.83 187.96 0)
			(effects
				(font
					(size 1.27 1.27)
				)
				(hide yes)
			)
		)
		(property "Datasheet" ""
			(at 36.83 187.96 0)
			(effects
				(font
					(size 1.27 1.27)
				)
				(hide yes)
			)
		)
		(property "Description" ""
			(at 36.83 187.96 0)
			(effects
				(font
					(size 1.27 1.27)
				)
				(hide yes)
			)
		)
		(property "Author" "Antmicro"
			(at 45.72 195.58 0)
			(effects
				(font
					(size 1.27 1.27)
					(thickness 0.15)
				)
				(justify left bottom)
				(hide yes)
			)
		)
		(property "License" "Apache-2.0"
			(at 45.72 198.12 0)
			(effects
				(font
					(size 1.27 1.27)
					(thickness 0.15)
				)
				(justify left bottom)
				(hide yes)
			)
		)
		(pin "1"
		)
		(instances
			(project "environment-sensor"
				(path ""
					(reference "#PWR03")
					(unit 1)
				)
			)
		)
	)
	(symbol
		(lib_id "antmicroResistors0402:R_5k1_0402")
		(at 78.74 104.14 90)
		(unit 1)
		(exclude_from_sim no)
		(in_bom yes)
		(on_board yes)
		(dnp no)
		(fields_autoplaced yes)
		(property "Reference" "R4"
			(at 81.28 100.3299 90)
			(effects
				(font
					(size 1.27 1.27)
					(thickness 0.15)
				)
				(justify right)
			)
		)
		(property "Value" "R_5k1_0402"
			(at 91.44 83.82 0)
			(effects
				(font
					(size 1.27 1.27)
					(thickness 0.15)
				)
				(justify left bottom)
				(hide yes)
			)
		)
		(property "Footprint" "antmicro-footprints:R_0402_1005Metric"
			(at 93.98 83.82 0)
			(effects
				(font
					(size 1.27 1.27)
					(thickness 0.15)
				)
				(justify left bottom)
				(hide yes)
			)
		)
		(property "Datasheet" "https://www.bourns.com/docs/product-datasheets/cr.pdf"
			(at 96.52 83.82 0)
			(effects
				(font
					(size 1.27 1.27)
					(thickness 0.15)
				)
				(justify left bottom)
				(hide yes)
			)
		)
		(property "Description" "SMD Chip Resistor, 5.1 kohm, ± 1%, 63 mW, 0402 [1005 Metric], Thick Film, General Purpose"
			(at 78.74 104.14 0)
			(effects
				(font
					(size 1.27 1.27)
				)
				(hide yes)
			)
		)
		(property "Manufacturer" "Bourns"
			(at 101.6 83.82 0)
			(effects
				(font
					(size 1.27 1.27)
					(thickness 0.15)
				)
				(justify left bottom)
				(hide yes)
			)
		)
		(property "MPN" "CR0402-FX-5101GLF"
			(at 99.06 83.82 0)
			(effects
				(font
					(size 1.27 1.27)
					(thickness 0.15)
				)
				(justify left bottom)
				(hide yes)
			)
		)
		(property "Val" "5k1"
			(at 81.28 102.8699 90)
			(effects
				(font
					(size 1.27 1.27)
					(thickness 0.15)
				)
				(justify right)
			)
		)
		(property "License" "Apache-2.0"
			(at 104.14 83.82 0)
			(effects
				(font
					(size 1.27 1.27)
					(thickness 0.15)
				)
				(justify left bottom)
				(hide yes)
			)
		)
		(property "Author" "Antmicro"
			(at 106.68 83.82 0)
			(effects
				(font
					(size 1.27 1.27)
					(thickness 0.15)
				)
				(justify left bottom)
				(hide yes)
			)
		)
		(property "Tolerance" "1%"
			(at 88.9 83.82 0)
			(effects
				(font
					(size 1.27 1.27)
				)
				(justify left bottom)
				(hide yes)
			)
		)
		(property "Public" "False"
			(at 109.22 83.82 0)
			(effects
				(font
					(size 1.27 1.27)
				)
				(justify left bottom)
				(hide yes)
			)
		)
		(pin "1"
		)
		(pin "2"
		)
		(instances
			(project "environment-sensor"
				(path ""
					(reference "R4")
					(unit 1)
				)
			)
		)
	)
	(symbol
		(lib_id "antmicroTestPoints:TP_1.5mm_SMD")
		(at 147.32 251.46 180)
		(unit 1)
		(exclude_from_sim no)
		(in_bom yes)
		(on_board yes)
		(dnp no)
		(fields_autoplaced yes)
		(property "Reference" "TP3"
			(at 140.335 250.19 0)
			(effects
				(font
					(size 1.27 1.27)
					(thickness 0.15)
				)
			)
		)
		(property "Value" "TP_1.5mm_SMD"
			(at 132.08 243.84 0)
			(effects
				(font
					(size 1.27 1.27)
					(thickness 0.15)
				)
				(justify left bottom)
				(hide yes)
			)
		)
		(property "Footprint" "antmicro-footprints:TP_SMD_1.5mm"
			(at 132.08 241.3 0)
			(effects
				(font
					(size 1.27 1.27)
					(thickness 0.15)
				)
				(justify left bottom)
				(hide yes)
			)
		)
		(property "Datasheet" ""
			(at 132.08 238.76 0)
			(effects
				(font
					(size 1.27 1.27)
					(thickness 0.15)
				)
				(justify left bottom)
				(hide yes)
			)
		)
		(property "Description" "test point, SMT"
			(at 147.32 251.46 0)
			(effects
				(font
					(size 1.27 1.27)
				)
				(hide yes)
			)
		)
		(property "MPN" ""
			(at 147.32 251.46 0)
			(effects
				(font
					(size 1.27 1.27)
				)
				(hide yes)
			)
		)
		(property "Manufacturer" ""
			(at 147.32 251.46 0)
			(effects
				(font
					(size 1.27 1.27)
				)
				(hide yes)
			)
		)
		(property "Author" "Antmicro"
			(at 132.08 236.22 0)
			(effects
				(font
					(size 1.27 1.27)
					(thickness 0.15)
				)
				(justify left bottom)
				(hide yes)
			)
		)
		(property "License" "Apache-2.0"
			(at 132.08 233.68 0)
			(effects
				(font
					(size 1.27 1.27)
					(thickness 0.15)
				)
				(justify left bottom)
				(hide yes)
			)
		)
		(property "Public" "False"
			(at 132.08 231.14 0)
			(effects
				(font
					(size 1.27 1.27)
				)
				(justify left bottom)
				(hide yes)
			)
		)
		(pin "1"
		)
		(instances
			(project "environment-sensor"
				(path ""
					(reference "TP3")
					(unit 1)
				)
			)
		)
	)
	(symbol
		(lib_id "antmicropower:GND")
		(at 365.76 134.62 0)
		(mirror y)
		(unit 1)
		(exclude_from_sim no)
		(in_bom yes)
		(on_board yes)
		(dnp no)
		(fields_autoplaced yes)
		(property "Reference" "#PWR067"
			(at 365.76 140.97 0)
			(effects
				(font
					(size 1.27 1.27)
				)
				(hide yes)
			)
		)
		(property "Value" "GND"
			(at 365.76 139.7 0)
			(effects
				(font
					(size 1.27 1.27)
				)
			)
		)
		(property "Footprint" ""
			(at 365.76 134.62 0)
			(effects
				(font
					(size 1.27 1.27)
				)
				(hide yes)
			)
		)
		(property "Datasheet" ""
			(at 365.76 134.62 0)
			(effects
				(font
					(size 1.27 1.27)
				)
				(hide yes)
			)
		)
		(property "Description" ""
			(at 365.76 134.62 0)
			(effects
				(font
					(size 1.27 1.27)
				)
				(hide yes)
			)
		)
		(property "Author" "Antmicro"
			(at 356.87 142.24 0)
			(effects
				(font
					(size 1.27 1.27)
					(thickness 0.15)
				)
				(justify left bottom)
				(hide yes)
			)
		)
		(property "License" "Apache-2.0"
			(at 356.87 144.78 0)
			(effects
				(font
					(size 1.27 1.27)
					(thickness 0.15)
				)
				(justify left bottom)
				(hide yes)
			)
		)
		(pin "1"
		)
		(instances
			(project "environment-sensor"
				(path ""
					(reference "#PWR067")
					(unit 1)
				)
			)
		)
	)
	(symbol
		(lib_id "antmicropower:+5V")
		(at 58.42 182.88 0)
		(unit 1)
		(exclude_from_sim no)
		(in_bom yes)
		(on_board yes)
		(dnp no)
		(fields_autoplaced yes)
		(property "Reference" "#PWR06"
			(at 73.66 185.42 0)
			(effects
				(font
					(size 1.27 1.27)
					(thickness 0.15)
				)
				(justify left bottom)
				(hide yes)
			)
		)
		(property "Value" "+5V"
			(at 60.325 179.705 0)
			(effects
				(font
					(size 1.27 1.27)
					(thickness 0.15)
				)
			)
		)
		(property "Footprint" ""
			(at 73.66 190.5 0)
			(effects
				(font
					(size 1.27 1.27)
					(thickness 0.15)
				)
				(justify left bottom)
				(hide yes)
			)
		)
		(property "Datasheet" ""
			(at 73.66 193.04 0)
			(effects
				(font
					(size 1.27 1.27)
					(thickness 0.15)
				)
				(justify left bottom)
				(hide yes)
			)
		)
		(property "Description" ""
			(at 58.42 182.88 0)
			(effects
				(font
					(size 1.27 1.27)
				)
				(hide yes)
			)
		)
		(property "Author" "Antmicro"
			(at 73.66 190.5 0)
			(effects
				(font
					(size 1.27 1.27)
					(thickness 0.15)
				)
				(justify left bottom)
				(hide yes)
			)
		)
		(property "License" "Apache-2.0"
			(at 73.66 193.04 0)
			(effects
				(font
					(size 1.27 1.27)
					(thickness 0.15)
				)
				(justify left bottom)
				(hide yes)
			)
		)
		(pin "1"
		)
		(instances
			(project "environment-sensor"
				(path ""
					(reference "#PWR06")
					(unit 1)
				)
			)
		)
	)
	(symbol
		(lib_id "antmicroCapacitors0402:C_4u7_0402")
		(at 199.39 55.88 90)
		(unit 1)
		(exclude_from_sim no)
		(in_bom yes)
		(on_board yes)
		(dnp no)
		(fields_autoplaced yes)
		(property "Reference" "C10"
			(at 201.93 52.0635 90)
			(effects
				(font
					(size 1.27 1.27)
					(thickness 0.15)
				)
				(justify right)
			)
		)
		(property "Value" "C_4u7_0402"
			(at 209.55 35.56 0)
			(effects
				(font
					(size 1.27 1.27)
					(thickness 0.15)
				)
				(justify left bottom)
				(hide yes)
			)
		)
		(property "Footprint" "antmicro-footprints:C_0402_1005Metric"
			(at 212.09 35.56 0)
			(effects
				(font
					(size 1.27 1.27)
					(thickness 0.15)
				)
				(justify left bottom)
				(hide yes)
			)
		)
		(property "Datasheet" "https://www.murata.com/products/productdetail?partno=GRM155R61A475MEAA%23"
			(at 214.63 35.56 0)
			(effects
				(font
					(size 1.27 1.27)
					(thickness 0.15)
				)
				(justify left bottom)
				(hide yes)
			)
		)
		(property "Description" "SMD Multilayer Ceramic Capacitor, 4.7 µF, 10 V, 0402 [1005 Metric], ± 20%, X5R, GRM Series"
			(at 199.39 55.88 0)
			(effects
				(font
					(size 1.27 1.27)
				)
				(hide yes)
			)
		)
		(property "Manufacturer" "Murata"
			(at 219.71 35.56 0)
			(effects
				(font
					(size 1.27 1.27)
					(thickness 0.15)
				)
				(justify left bottom)
				(hide yes)
			)
		)
		(property "MPN" "GRM155R61A475MEAAD"
			(at 217.17 35.56 0)
			(effects
				(font
					(size 1.27 1.27)
					(thickness 0.15)
				)
				(justify left bottom)
				(hide yes)
			)
		)
		(property "Val" "4u7"
			(at 201.93 54.6035 90)
			(effects
				(font
					(size 1.27 1.27)
					(thickness 0.15)
				)
				(justify right)
			)
		)
		(property "License" "Apache-2.0"
			(at 222.25 35.56 0)
			(effects
				(font
					(size 1.27 1.27)
					(thickness 0.15)
				)
				(justify left bottom)
				(hide yes)
			)
		)
		(property "Author" "Antmicro"
			(at 224.79 35.56 0)
			(effects
				(font
					(size 1.27 1.27)
					(thickness 0.15)
				)
				(justify left bottom)
				(hide yes)
			)
		)
		(property "Voltage" ""
			(at 227.33 35.56 0)
			(effects
				(font
					(size 1.27 1.27)
				)
				(justify left bottom)
				(hide yes)
			)
		)
		(property "Dielectric" ""
			(at 229.87 35.56 0)
			(effects
				(font
					(size 1.27 1.27)
				)
				(justify left bottom)
				(hide yes)
			)
		)
		(property "Public" "False"
			(at 232.41 35.56 0)
			(effects
				(font
					(size 1.27 1.27)
				)
				(justify left bottom)
				(hide yes)
			)
		)
		(pin "1"
		)
		(pin "2"
		)
		(instances
			(project "environment-sensor"
				(path ""
					(reference "C10")
					(unit 1)
				)
			)
		)
	)
	(symbol
		(lib_id "antmicroTestPoints:TP_1.5mm_SMD")
		(at 147.32 256.54 180)
		(unit 1)
		(exclude_from_sim no)
		(in_bom yes)
		(on_board yes)
		(dnp no)
		(fields_autoplaced yes)
		(property "Reference" "TP4"
			(at 140.335 254.635 0)
			(effects
				(font
					(size 1.27 1.27)
					(thickness 0.15)
				)
			)
		)
		(property "Value" "TP_1.5mm_SMD"
			(at 132.08 248.92 0)
			(effects
				(font
					(size 1.27 1.27)
					(thickness 0.15)
				)
				(justify left bottom)
				(hide yes)
			)
		)
		(property "Footprint" "antmicro-footprints:TP_SMD_1.5mm"
			(at 132.08 246.38 0)
			(effects
				(font
					(size 1.27 1.27)
					(thickness 0.15)
				)
				(justify left bottom)
				(hide yes)
			)
		)
		(property "Datasheet" ""
			(at 132.08 243.84 0)
			(effects
				(font
					(size 1.27 1.27)
					(thickness 0.15)
				)
				(justify left bottom)
				(hide yes)
			)
		)
		(property "Description" "test point, SMT"
			(at 147.32 256.54 0)
			(effects
				(font
					(size 1.27 1.27)
				)
				(hide yes)
			)
		)
		(property "MPN" ""
			(at 147.32 256.54 0)
			(effects
				(font
					(size 1.27 1.27)
				)
				(hide yes)
			)
		)
		(property "Manufacturer" ""
			(at 147.32 256.54 0)
			(effects
				(font
					(size 1.27 1.27)
				)
				(hide yes)
			)
		)
		(property "Author" "Antmicro"
			(at 132.08 241.3 0)
			(effects
				(font
					(size 1.27 1.27)
					(thickness 0.15)
				)
				(justify left bottom)
				(hide yes)
			)
		)
		(property "License" "Apache-2.0"
			(at 132.08 238.76 0)
			(effects
				(font
					(size 1.27 1.27)
					(thickness 0.15)
				)
				(justify left bottom)
				(hide yes)
			)
		)
		(property "Public" "False"
			(at 132.08 236.22 0)
			(effects
				(font
					(size 1.27 1.27)
				)
				(justify left bottom)
				(hide yes)
			)
		)
		(pin "1"
		)
		(instances
			(project "environment-sensor"
				(path ""
					(reference "TP4")
					(unit 1)
				)
			)
		)
	)
	(symbol
		(lib_id "antmicroLEDIndicationDiscrete:LED_G_0603_KP-1608ZGC")
		(at 135.89 52.07 270)
		(unit 1)
		(exclude_from_sim no)
		(in_bom yes)
		(on_board yes)
		(dnp no)
		(fields_autoplaced yes)
		(property "Reference" "LD1"
			(at 139.7 55.88 90)
			(effects
				(font
					(size 1.27 1.27)
					(thickness 0.15)
				)
				(justify left)
			)
		)
		(property "Value" "LED_G_0603_KP-1608ZGC"
			(at 139.7 57.1499 90)
			(effects
				(font
					(size 1.27 1.27)
					(thickness 0.15)
				)
				(justify left)
				(hide yes)
			)
		)
		(property "Footprint" "antmicro-footprints:LED_0603_1608Metric_G"
			(at 125.73 74.93 0)
			(effects
				(font
					(size 1.27 1.27)
					(thickness 0.15)
				)
				(justify left bottom)
				(hide yes)
			)
		)
		(property "Datasheet" "https://www.kingbright.com/attachments/file/psearch/000/00/00/KP-1608ZGC(Ver.19B).pdf"
			(at 123.19 74.93 0)
			(effects
				(font
					(size 1.27 1.27)
					(thickness 0.15)
				)
				(justify left bottom)
				(hide yes)
			)
		)
		(property "Description" "LED, Green, SMD, 0603, 20 mA, 3.3 V, 525 nm"
			(at 135.89 52.07 0)
			(effects
				(font
					(size 1.27 1.27)
				)
				(hide yes)
			)
		)
		(property "MPN" "KP-1608ZGC"
			(at 120.65 74.93 0)
			(effects
				(font
					(size 1.27 1.27)
					(thickness 0.15)
				)
				(justify left bottom)
				(hide yes)
			)
		)
		(property "Manufacturer" "Kingbright"
			(at 118.11 74.93 0)
			(effects
				(font
					(size 1.27 1.27)
					(thickness 0.15)
				)
				(justify left bottom)
				(hide yes)
			)
		)
		(property "Author" "Antmicro"
			(at 115.57 74.93 0)
			(effects
				(font
					(size 1.27 1.27)
					(thickness 0.15)
				)
				(justify left bottom)
				(hide yes)
			)
		)
		(property "License" "Apache-2.0"
			(at 113.03 74.93 0)
			(effects
				(font
					(size 1.27 1.27)
					(thickness 0.15)
				)
				(justify left bottom)
				(hide yes)
			)
		)
		(property "Color" "Green"
			(at 130.81 72.39 0)
			(effects
				(font
					(size 1.27 1.27)
				)
				(justify left bottom)
			)
		)
		(property "Public" "False"
			(at 118.11 72.39 0)
			(effects
				(font
					(size 1.27 1.27)
				)
				(justify left bottom)
				(hide yes)
			)
		)
		(pin "1"
		)
		(pin "2"
		)
		(instances
			(project "environment-sensor"
				(path ""
					(reference "LD1")
					(unit 1)
				)
			)
		)
	)
	(symbol
		(lib_id "antmicropower:GND")
		(at 68.58 222.25 0)
		(unit 1)
		(exclude_from_sim no)
		(in_bom yes)
		(on_board yes)
		(dnp no)
		(fields_autoplaced yes)
		(property "Reference" "#PWR09"
			(at 68.58 228.6 0)
			(effects
				(font
					(size 1.27 1.27)
				)
				(hide yes)
			)
		)
		(property "Value" "GND"
			(at 68.58 227.33 0)
			(effects
				(font
					(size 1.27 1.27)
				)
			)
		)
		(property "Footprint" ""
			(at 68.58 222.25 0)
			(effects
				(font
					(size 1.27 1.27)
				)
				(hide yes)
			)
		)
		(property "Datasheet" ""
			(at 68.58 222.25 0)
			(effects
				(font
					(size 1.27 1.27)
				)
				(hide yes)
			)
		)
		(property "Description" ""
			(at 68.58 222.25 0)
			(effects
				(font
					(size 1.27 1.27)
				)
				(hide yes)
			)
		)
		(property "Author" "Antmicro"
			(at 77.47 229.87 0)
			(effects
				(font
					(size 1.27 1.27)
					(thickness 0.15)
				)
				(justify left bottom)
				(hide yes)
			)
		)
		(property "License" "Apache-2.0"
			(at 77.47 232.41 0)
			(effects
				(font
					(size 1.27 1.27)
					(thickness 0.15)
				)
				(justify left bottom)
				(hide yes)
			)
		)
		(pin "1"
		)
		(instances
			(project "environment-sensor"
				(path ""
					(reference "#PWR09")
					(unit 1)
				)
			)
		)
	)
	(symbol
		(lib_id "antmicropower:GND")
		(at 45.72 187.96 0)
		(unit 1)
		(exclude_from_sim no)
		(in_bom yes)
		(on_board yes)
		(dnp no)
		(fields_autoplaced yes)
		(property "Reference" "#PWR04"
			(at 45.72 194.31 0)
			(effects
				(font
					(size 1.27 1.27)
				)
				(hide yes)
			)
		)
		(property "Value" "GND"
			(at 45.72 193.04 0)
			(effects
				(font
					(size 1.27 1.27)
				)
			)
		)
		(property "Footprint" ""
			(at 45.72 187.96 0)
			(effects
				(font
					(size 1.27 1.27)
				)
				(hide yes)
			)
		)
		(property "Datasheet" ""
			(at 45.72 187.96 0)
			(effects
				(font
					(size 1.27 1.27)
				)
				(hide yes)
			)
		)
		(property "Description" ""
			(at 45.72 187.96 0)
			(effects
				(font
					(size 1.27 1.27)
				)
				(hide yes)
			)
		)
		(property "Author" "Antmicro"
			(at 54.61 195.58 0)
			(effects
				(font
					(size 1.27 1.27)
					(thickness 0.15)
				)
				(justify left bottom)
				(hide yes)
			)
		)
		(property "License" "Apache-2.0"
			(at 54.61 198.12 0)
			(effects
				(font
					(size 1.27 1.27)
					(thickness 0.15)
				)
				(justify left bottom)
				(hide yes)
			)
		)
		(pin "1"
		)
		(instances
			(project "environment-sensor"
				(path ""
					(reference "#PWR04")
					(unit 1)
				)
			)
		)
	)
	(symbol
		(lib_id "antmicroResistors0402:R_0R_0402")
		(at 135.89 193.04 0)
		(unit 1)
		(exclude_from_sim no)
		(in_bom no)
		(on_board yes)
		(dnp yes)
		(fields_autoplaced yes)
		(property "Reference" "R16"
			(at 135.89 195.58 0)
			(effects
				(font
					(size 1.27 1.27)
					(thickness 0.15)
				)
			)
		)
		(property "Value" "R_0R_0402"
			(at 156.21 205.74 0)
			(effects
				(font
					(size 1.27 1.27)
					(thickness 0.15)
				)
				(justify left bottom)
				(hide yes)
			)
		)
		(property "Footprint" "antmicro-footprints:R_0402_1005Metric"
			(at 156.21 208.28 0)
			(effects
				(font
					(size 1.27 1.27)
					(thickness 0.15)
				)
				(justify left bottom)
				(hide yes)
			)
		)
		(property "Datasheet" "https://industrial.panasonic.com/cdbs/www-data/pdf/RDA0000/AOA0000C301.pdf"
			(at 156.21 210.82 0)
			(effects
				(font
					(size 1.27 1.27)
					(thickness 0.15)
				)
				(justify left bottom)
				(hide yes)
			)
		)
		(property "Description" "SMD Chip Resistor, Jumper, 0 ohm, 100 mW, 0402 [1005 Metric], Thick Film, General Purpose"
			(at 135.89 193.04 0)
			(effects
				(font
					(size 1.27 1.27)
				)
				(hide yes)
			)
		)
		(property "Manufacturer" "Panasonic"
			(at 156.21 215.9 0)
			(effects
				(font
					(size 1.27 1.27)
					(thickness 0.15)
				)
				(justify left bottom)
				(hide yes)
			)
		)
		(property "MPN" "ERJ2GE0R00X"
			(at 156.21 213.36 0)
			(effects
				(font
					(size 1.27 1.27)
					(thickness 0.15)
				)
				(justify left bottom)
				(hide yes)
			)
		)
		(property "Val" "0R"
			(at 139.7 195.58 0)
			(effects
				(font
					(size 1.27 1.27)
					(thickness 0.15)
				)
			)
		)
		(property "License" "Apache-2.0"
			(at 156.21 218.44 0)
			(effects
				(font
					(size 1.27 1.27)
					(thickness 0.15)
				)
				(justify left bottom)
				(hide yes)
			)
		)
		(property "Author" "Antmicro"
			(at 156.21 220.98 0)
			(effects
				(font
					(size 1.27 1.27)
					(thickness 0.15)
				)
				(justify left bottom)
				(hide yes)
			)
		)
		(property "Tolerance" "~"
			(at 156.21 203.2 0)
			(effects
				(font
					(size 1.27 1.27)
				)
				(justify left bottom)
				(hide yes)
			)
		)
		(property "Current" "1A"
			(at 138.43 193.04 0)
			(effects
				(font
					(size 1.27 1.27)
					(thickness 0.15)
				)
				(hide yes)
			)
		)
		(property "Public" "False"
			(at 156.21 223.52 0)
			(effects
				(font
					(size 1.27 1.27)
				)
				(justify left bottom)
				(hide yes)
			)
		)
		(pin "1"
		)
		(pin "2"
		)
		(instances
			(project "environment-sensor"
				(path ""
					(reference "R16")
					(unit 1)
				)
			)
		)
	)
	(symbol
		(lib_id "antmicropower:GND")
		(at 149.86 73.66 0)
		(unit 1)
		(exclude_from_sim no)
		(in_bom yes)
		(on_board yes)
		(dnp no)
		(fields_autoplaced yes)
		(property "Reference" "#PWR020"
			(at 149.86 80.01 0)
			(effects
				(font
					(size 1.27 1.27)
				)
				(hide yes)
			)
		)
		(property "Value" "GND"
			(at 149.86 78.74 0)
			(effects
				(font
					(size 1.27 1.27)
				)
			)
		)
		(property "Footprint" ""
			(at 149.86 73.66 0)
			(effects
				(font
					(size 1.27 1.27)
				)
				(hide yes)
			)
		)
		(property "Datasheet" ""
			(at 149.86 73.66 0)
			(effects
				(font
					(size 1.27 1.27)
				)
				(hide yes)
			)
		)
		(property "Description" ""
			(at 149.86 73.66 0)
			(effects
				(font
					(size 1.27 1.27)
				)
				(hide yes)
			)
		)
		(property "Author" "Antmicro"
			(at 158.75 81.28 0)
			(effects
				(font
					(size 1.27 1.27)
					(thickness 0.15)
				)
				(justify left bottom)
				(hide yes)
			)
		)
		(property "License" "Apache-2.0"
			(at 158.75 83.82 0)
			(effects
				(font
					(size 1.27 1.27)
					(thickness 0.15)
				)
				(justify left bottom)
				(hide yes)
			)
		)
		(pin "1"
		)
		(instances
			(project "environment-sensor"
				(path ""
					(reference "#PWR020")
					(unit 1)
				)
			)
		)
	)
	(symbol
		(lib_id "antmicropower:+3V3")
		(at 365.76 113.03 0)
		(unit 1)
		(exclude_from_sim no)
		(in_bom yes)
		(on_board yes)
		(dnp no)
		(fields_autoplaced yes)
		(property "Reference" "#PWR066"
			(at 365.76 116.84 0)
			(effects
				(font
					(size 1.27 1.27)
				)
				(hide yes)
			)
		)
		(property "Value" "+3V3"
			(at 365.76 107.95 0)
			(effects
				(font
					(size 1.27 1.27)
				)
			)
		)
		(property "Footprint" ""
			(at 365.76 113.03 0)
			(effects
				(font
					(size 1.27 1.27)
				)
				(hide yes)
			)
		)
		(property "Datasheet" ""
			(at 365.76 113.03 0)
			(effects
				(font
					(size 1.27 1.27)
				)
				(hide yes)
			)
		)
		(property "Description" ""
			(at 365.76 113.03 0)
			(effects
				(font
					(size 1.27 1.27)
				)
				(hide yes)
			)
		)
		(property "Author" "Antmicro"
			(at 381 115.57 0)
			(effects
				(font
					(size 1.27 1.27)
					(thickness 0.15)
				)
				(justify left bottom)
				(hide yes)
			)
		)
		(property "License" "Apache-2.0"
			(at 381 118.11 0)
			(effects
				(font
					(size 1.27 1.27)
					(thickness 0.15)
				)
				(justify left bottom)
				(hide yes)
			)
		)
		(pin "1"
		)
		(instances
			(project "environment-sensor"
				(path ""
					(reference "#PWR066")
					(unit 1)
				)
			)
		)
	)
	(symbol
		(lib_id "antmicropower:GND")
		(at 233.68 261.62 0)
		(mirror y)
		(unit 1)
		(exclude_from_sim no)
		(in_bom yes)
		(on_board yes)
		(dnp no)
		(fields_autoplaced yes)
		(property "Reference" "#PWR039"
			(at 233.68 267.97 0)
			(effects
				(font
					(size 1.27 1.27)
				)
				(hide yes)
			)
		)
		(property "Value" "GND"
			(at 236.22 262.8899 0)
			(effects
				(font
					(size 1.27 1.27)
				)
				(justify right)
			)
		)
		(property "Footprint" ""
			(at 233.68 261.62 0)
			(effects
				(font
					(size 1.27 1.27)
				)
				(hide yes)
			)
		)
		(property "Datasheet" ""
			(at 233.68 261.62 0)
			(effects
				(font
					(size 1.27 1.27)
				)
				(hide yes)
			)
		)
		(property "Description" ""
			(at 233.68 261.62 0)
			(effects
				(font
					(size 1.27 1.27)
				)
				(hide yes)
			)
		)
		(property "Author" "Antmicro"
			(at 224.79 269.24 0)
			(effects
				(font
					(size 1.27 1.27)
					(thickness 0.15)
				)
				(justify left bottom)
				(hide yes)
			)
		)
		(property "License" "Apache-2.0"
			(at 224.79 271.78 0)
			(effects
				(font
					(size 1.27 1.27)
					(thickness 0.15)
				)
				(justify left bottom)
				(hide yes)
			)
		)
		(pin "1"
		)
		(instances
			(project "environment-sensor"
				(path ""
					(reference "#PWR039")
					(unit 1)
				)
			)
		)
	)
	(symbol
		(lib_id "antmicroMemory:MB85RC1MTPNF-G")
		(at 287.02 43.18 0)
		(mirror y)
		(unit 1)
		(exclude_from_sim no)
		(in_bom yes)
		(on_board yes)
		(dnp no)
		(fields_autoplaced yes)
		(property "Reference" "U4"
			(at 280.67 41.91 0)
			(effects
				(font
					(size 1.27 1.27)
					(thickness 0.15)
				)
				(justify left)
			)
		)
		(property "Value" "MB85RC1MTPNF-G"
			(at 295.91 44.45 0)
			(effects
				(font
					(size 1.27 1.27)
					(thickness 0.15)
				)
				(justify left)
			)
		)
		(property "Footprint" "antmicro-footprints:SOP-8_3.9x5.05mm_P1.27mm"
			(at 251.46 53.34 0)
			(effects
				(font
					(size 1.27 1.27)
					(thickness 0.15)
				)
				(justify left bottom)
				(hide yes)
			)
		)
		(property "Datasheet" "https://www.fujitsu.com/jp/group/fsm/en/documents/products/feram/lineup/MB85RC1MT-DS501-00027-5v0-E.pdf"
			(at 251.46 55.88 0)
			(effects
				(font
					(size 1.27 1.27)
					(thickness 0.15)
				)
				(justify left bottom)
				(hide yes)
			)
		)
		(property "Description" "FRAM (Ferroelectric RAM) Memory IC 1Mbit I²C 3.4 MHz 130 ns 8-SOP"
			(at 287.02 43.18 0)
			(effects
				(font
					(size 1.27 1.27)
				)
				(hide yes)
			)
		)
		(property "MPN" "MB85RC1MTPNF-G-JNERE1"
			(at 251.46 58.42 0)
			(effects
				(font
					(size 1.27 1.27)
					(thickness 0.15)
				)
				(justify left bottom)
				(hide yes)
			)
		)
		(property "Manufacturer" "Fujitsu"
			(at 251.46 60.96 0)
			(effects
				(font
					(size 1.27 1.27)
					(thickness 0.15)
				)
				(justify left bottom)
				(hide yes)
			)
		)
		(property "Author" "Antmicro"
			(at 251.46 63.5 0)
			(effects
				(font
					(size 1.27 1.27)
					(thickness 0.15)
				)
				(justify left bottom)
				(hide yes)
			)
		)
		(property "License" "Apache-2.0"
			(at 251.46 66.04 0)
			(effects
				(font
					(size 1.27 1.27)
					(thickness 0.15)
				)
				(justify left bottom)
				(hide yes)
			)
		)
		(pin "7"
		)
		(pin "4"
		)
		(pin "8"
		)
		(pin "6"
		)
		(pin "2"
		)
		(pin "5"
		)
		(pin "3"
		)
		(pin "1"
		)
		(instances
			(project "environment-sensor"
				(path ""
					(reference "U4")
					(unit 1)
				)
			)
		)
	)
	(symbol
		(lib_id "antmicropower:+3V3")
		(at 306.07 137.16 0)
		(unit 1)
		(exclude_from_sim no)
		(in_bom yes)
		(on_board yes)
		(dnp no)
		(fields_autoplaced yes)
		(property "Reference" "#PWR054"
			(at 306.07 140.97 0)
			(effects
				(font
					(size 1.27 1.27)
				)
				(hide yes)
			)
		)
		(property "Value" "+3V3"
			(at 306.07 132.08 0)
			(effects
				(font
					(size 1.27 1.27)
				)
			)
		)
		(property "Footprint" ""
			(at 306.07 137.16 0)
			(effects
				(font
					(size 1.27 1.27)
				)
				(hide yes)
			)
		)
		(property "Datasheet" ""
			(at 306.07 137.16 0)
			(effects
				(font
					(size 1.27 1.27)
				)
				(hide yes)
			)
		)
		(property "Description" ""
			(at 306.07 137.16 0)
			(effects
				(font
					(size 1.27 1.27)
				)
				(hide yes)
			)
		)
		(property "Author" "Antmicro"
			(at 321.31 139.7 0)
			(effects
				(font
					(size 1.27 1.27)
					(thickness 0.15)
				)
				(justify left bottom)
				(hide yes)
			)
		)
		(property "License" "Apache-2.0"
			(at 321.31 142.24 0)
			(effects
				(font
					(size 1.27 1.27)
					(thickness 0.15)
				)
				(justify left bottom)
				(hide yes)
			)
		)
		(pin "1"
		)
		(instances
			(project "environment-sensor"
				(path ""
					(reference "#PWR054")
					(unit 1)
				)
			)
		)
	)
	(symbol
		(lib_id "antmicroCapacitors0402:C_100n_0402")
		(at 204.47 113.03 90)
		(mirror x)
		(unit 1)
		(exclude_from_sim no)
		(in_bom yes)
		(on_board yes)
		(dnp no)
		(fields_autoplaced yes)
		(property "Reference" "C22"
			(at 201.93 114.3062 90)
			(effects
				(font
					(size 1.27 1.27)
					(thickness 0.15)
				)
				(justify left)
			)
		)
		(property "Value" "C_100n_0402"
			(at 214.63 133.35 0)
			(effects
				(font
					(size 1.27 1.27)
					(thickness 0.15)
				)
				(justify left bottom)
				(hide yes)
			)
		)
		(property "Footprint" "antmicro-footprints:C_0402_1005Metric"
			(at 217.17 133.35 0)
			(effects
				(font
					(size 1.27 1.27)
					(thickness 0.15)
				)
				(justify left bottom)
				(hide yes)
			)
		)
		(property "Datasheet" "https://www.murata.com/products/productdetail?partno=GRM155R61H104KE14%23"
			(at 219.71 133.35 0)
			(effects
				(font
					(size 1.27 1.27)
					(thickness 0.15)
				)
				(justify left bottom)
				(hide yes)
			)
		)
		(property "Description" "SMD Multilayer Ceramic Capacitor, 0.1 µF, 50 V, 0402 [1005 Metric], ± 10%, X5R, GRM Series"
			(at 204.47 113.03 0)
			(effects
				(font
					(size 1.27 1.27)
				)
				(hide yes)
			)
		)
		(property "Manufacturer" "Murata"
			(at 224.79 133.35 0)
			(effects
				(font
					(size 1.27 1.27)
					(thickness 0.15)
				)
				(justify left bottom)
				(hide yes)
			)
		)
		(property "MPN" "GRM155R61H104KE14D"
			(at 222.25 133.35 0)
			(effects
				(font
					(size 1.27 1.27)
					(thickness 0.15)
				)
				(justify left bottom)
				(hide yes)
			)
		)
		(property "Val" "100n"
			(at 201.93 116.8462 90)
			(effects
				(font
					(size 1.27 1.27)
					(thickness 0.15)
				)
				(justify left)
			)
		)
		(property "License" "Apache-2.0"
			(at 227.33 133.35 0)
			(effects
				(font
					(size 1.27 1.27)
					(thickness 0.15)
				)
				(justify left bottom)
				(hide yes)
			)
		)
		(property "Author" "Antmicro"
			(at 229.87 133.35 0)
			(effects
				(font
					(size 1.27 1.27)
					(thickness 0.15)
				)
				(justify left bottom)
				(hide yes)
			)
		)
		(property "Voltage" "50V"
			(at 232.41 133.35 0)
			(effects
				(font
					(size 1.27 1.27)
				)
				(justify left bottom)
				(hide yes)
			)
		)
		(property "Dielectric" "X5R"
			(at 234.95 133.35 0)
			(effects
				(font
					(size 1.27 1.27)
				)
				(justify left bottom)
				(hide yes)
			)
		)
		(property "Public" "False"
			(at 237.49 133.35 0)
			(effects
				(font
					(size 1.27 1.27)
				)
				(justify left bottom)
				(hide yes)
			)
		)
		(pin "1"
		)
		(pin "2"
		)
		(instances
			(project "environment-sensor"
				(path ""
					(reference "C22")
					(unit 1)
				)
			)
		)
	)
	(symbol
		(lib_id "antmicropower:GND")
		(at 293.37 198.12 0)
		(mirror y)
		(unit 1)
		(exclude_from_sim no)
		(in_bom yes)
		(on_board yes)
		(dnp no)
		(fields_autoplaced yes)
		(property "Reference" "#PWR050"
			(at 293.37 204.47 0)
			(effects
				(font
					(size 1.27 1.27)
				)
				(hide yes)
			)
		)
		(property "Value" "GND"
			(at 293.37 201.93 0)
			(effects
				(font
					(size 1.27 1.27)
				)
			)
		)
		(property "Footprint" ""
			(at 293.37 198.12 0)
			(effects
				(font
					(size 1.27 1.27)
				)
				(hide yes)
			)
		)
		(property "Datasheet" ""
			(at 293.37 198.12 0)
			(effects
				(font
					(size 1.27 1.27)
				)
				(hide yes)
			)
		)
		(property "Description" ""
			(at 293.37 198.12 0)
			(effects
				(font
					(size 1.27 1.27)
				)
				(hide yes)
			)
		)
		(property "Author" "Antmicro"
			(at 284.48 205.74 0)
			(effects
				(font
					(size 1.27 1.27)
					(thickness 0.15)
				)
				(justify left bottom)
				(hide yes)
			)
		)
		(property "License" "Apache-2.0"
			(at 284.48 208.28 0)
			(effects
				(font
					(size 1.27 1.27)
					(thickness 0.15)
				)
				(justify left bottom)
				(hide yes)
			)
		)
		(pin "1"
		)
		(instances
			(project "environment-sensor"
				(path ""
					(reference "#PWR050")
					(unit 1)
				)
			)
		)
	)
	(symbol
		(lib_id "antmicroCapacitors0402:C_100n_0402")
		(at 45.72 83.82 180)
		(unit 1)
		(exclude_from_sim no)
		(in_bom yes)
		(on_board yes)
		(dnp no)
		(fields_autoplaced yes)
		(property "Reference" "C2"
			(at 43.1736 77.47 0)
			(effects
				(font
					(size 1.27 1.27)
					(thickness 0.15)
				)
			)
		)
		(property "Value" "C_100n_0402"
			(at 25.4 73.66 0)
			(effects
				(font
					(size 1.27 1.27)
					(thickness 0.15)
				)
				(justify left bottom)
				(hide yes)
			)
		)
		(property "Footprint" "antmicro-footprints:C_0402_1005Metric"
			(at 25.4 71.12 0)
			(effects
				(font
					(size 1.27 1.27)
					(thickness 0.15)
				)
				(justify left bottom)
				(hide yes)
			)
		)
		(property "Datasheet" "https://www.murata.com/products/productdetail?partno=GRM155R61H104KE14%23"
			(at 25.4 68.58 0)
			(effects
				(font
					(size 1.27 1.27)
					(thickness 0.15)
				)
				(justify left bottom)
				(hide yes)
			)
		)
		(property "Description" "SMD Multilayer Ceramic Capacitor, 0.1 µF, 50 V, 0402 [1005 Metric], ± 10%, X5R, GRM Series"
			(at 45.72 83.82 0)
			(effects
				(font
					(size 1.27 1.27)
				)
				(hide yes)
			)
		)
		(property "Manufacturer" "Murata"
			(at 25.4 63.5 0)
			(effects
				(font
					(size 1.27 1.27)
					(thickness 0.15)
				)
				(justify left bottom)
				(hide yes)
			)
		)
		(property "MPN" "GRM155R61H104KE14D"
			(at 25.4 66.04 0)
			(effects
				(font
					(size 1.27 1.27)
					(thickness 0.15)
				)
				(justify left bottom)
				(hide yes)
			)
		)
		(property "Val" "100n"
			(at 43.1736 80.01 0)
			(effects
				(font
					(size 1.27 1.27)
					(thickness 0.15)
				)
			)
		)
		(property "License" "Apache-2.0"
			(at 25.4 60.96 0)
			(effects
				(font
					(size 1.27 1.27)
					(thickness 0.15)
				)
				(justify left bottom)
				(hide yes)
			)
		)
		(property "Author" "Antmicro"
			(at 25.4 58.42 0)
			(effects
				(font
					(size 1.27 1.27)
					(thickness 0.15)
				)
				(justify left bottom)
				(hide yes)
			)
		)
		(property "Voltage" "50V"
			(at 25.4 55.88 0)
			(effects
				(font
					(size 1.27 1.27)
				)
				(justify left bottom)
				(hide yes)
			)
		)
		(property "Dielectric" "X5R"
			(at 25.4 53.34 0)
			(effects
				(font
					(size 1.27 1.27)
				)
				(justify left bottom)
				(hide yes)
			)
		)
		(property "Public" "False"
			(at 25.4 50.8 0)
			(effects
				(font
					(size 1.27 1.27)
				)
				(justify left bottom)
				(hide yes)
			)
		)
		(pin "1"
		)
		(pin "2"
		)
		(instances
			(project "environment-sensor"
				(path ""
					(reference "C2")
					(unit 1)
				)
			)
		)
	)
	(symbol
		(lib_id "antmicroHumidityMoistureSensors:BME280")
		(at 365.76 160.02 0)
		(unit 1)
		(exclude_from_sim no)
		(in_bom yes)
		(on_board yes)
		(dnp no)
		(fields_autoplaced yes)
		(property "Reference" "U6"
			(at 384.81 167.64 0)
			(effects
				(font
					(size 1.27 1.27)
					(thickness 0.15)
				)
				(justify left)
			)
		)
		(property "Value" "BME280"
			(at 384.81 170.18 0)
			(effects
				(font
					(size 1.27 1.27)
					(thickness 0.15)
				)
				(justify left)
			)
		)
		(property "Footprint" "antmicro-footprints:LGA-8_2.5x2.5mm_BME280"
			(at 398.78 170.18 0)
			(effects
				(font
					(size 1.27 1.27)
					(thickness 0.15)
				)
				(justify left bottom)
				(hide yes)
			)
		)
		(property "Datasheet" "https://www.bosch-sensortec.com/media/boschsensortec/downloads/datasheets/bst-bme280-ds002.pdf"
			(at 398.78 172.72 0)
			(effects
				(font
					(size 1.27 1.27)
					(thickness 0.15)
				)
				(justify left bottom)
				(hide yes)
			)
		)
		(property "Description" "Sensor"
			(at 365.76 160.02 0)
			(effects
				(font
					(size 1.27 1.27)
				)
				(hide yes)
			)
		)
		(property "MPN" "BME280"
			(at 398.78 175.26 0)
			(effects
				(font
					(size 1.27 1.27)
					(thickness 0.15)
				)
				(justify left bottom)
				(hide yes)
			)
		)
		(property "Manufacturer" "Bosch"
			(at 398.78 177.8 0)
			(effects
				(font
					(size 1.27 1.27)
					(thickness 0.15)
				)
				(justify left bottom)
				(hide yes)
			)
		)
		(property "Author" "Antmicro"
			(at 398.78 180.34 0)
			(effects
				(font
					(size 1.27 1.27)
					(thickness 0.15)
				)
				(justify left bottom)
				(hide yes)
			)
		)
		(property "License" "Apache-2.0"
			(at 398.78 182.88 0)
			(effects
				(font
					(size 1.27 1.27)
					(thickness 0.15)
				)
				(justify left bottom)
				(hide yes)
			)
		)
		(pin "6"
		)
		(pin "4"
		)
		(pin "1"
		)
		(pin "8"
		)
		(pin "5"
		)
		(pin "2"
		)
		(pin "3"
		)
		(pin "7"
		)
		(instances
			(project "environment-sensor"
				(path ""
					(reference "U6")
					(unit 1)
				)
			)
		)
	)
	(sheet_instances
		(path "/"
			(page "1")
		)
	)
)
